M48
INCH,TZ
T01C.001
T02C.01
T03C.012
T04C.014
T05C.01417
T06C.016
T07C.02
T08C.02913
T09C.035
T10C.04015
T11C.071
T12C.14
T13C.037
T14C.053
T15C.086
T16C.099
T17C.111
T18C.119
T19C.126
T20C.138
T21C.404
;LEADER: 12 
;HEADER: 
;CODE  : ASCII 
;FILE  : 16317-1-1-8.drl for board 16317-1.brd ... layers TOP and BOTTOM
;T01 Holesize 1. = 1.000000 Tolerance = +0.000000/-0.000000 PLATED MILS Quantity = 24
;T02 Holesize 2. = 10.000000 Tolerance = +0.000000/-0.000000 PLATED MILS Quantity = 290
;T03 Holesize 3. = 12.000000 Tolerance = +0.000000/-0.000000 PLATED MILS Quantity = 3193
;T04 Holesize 4. = 14.000000 Tolerance = +0.000000/-0.000000 PLATED MILS Quantity = 26
;T05 Holesize 5. = 14.170000 Tolerance = +0.000000/-0.000000 PLATED MILS Quantity = 568
;T06 Holesize 6. = 16.000000 Tolerance = +0.000000/-0.000000 PLATED MILS Quantity = 1772
;T07 Holesize 7. = 20.000000 Tolerance = +0.000000/-0.000000 PLATED MILS Quantity = 443
;T08 Holesize 8. = 29.130000 Tolerance = +0.000000/-0.000000 PLATED MILS Quantity = 62
;T09 Holesize 9. = 35.000000 Tolerance = +0.000000/-0.000000 PLATED MILS Quantity = 12
;T10 Holesize 10. = 40.150000 Tolerance = +0.000000/-0.000000 PLATED MILS Quantity = 56
;T11 Holesize 11. = 71.000000 Tolerance = +0.000000/-0.000000 PLATED MILS Quantity = 40
;T12 Holesize 12. = 140.000000 Tolerance = +0.000000/-0.000000 PLATED MILS Quantity = 6
;T13 Holesize 13. = 37.000000 Tolerance = +0.000000/-0.000000 NON_PLATED MILS Quantity = 36
;T14 Holesize 14. = 53.000000 Tolerance = +0.000000/-0.000000 NON_PLATED MILS Quantity = 36
;T15 Holesize 15. = 86.000000 Tolerance = +0.000000/-0.000000 NON_PLATED MILS Quantity = 8
;T16 Holesize 16. = 99.000000 Tolerance = +0.000000/-0.000000 NON_PLATED MILS Quantity = 2
;T17 Holesize 17. = 111.000000 Tolerance = +0.000000/-0.000000 NON_PLATED MILS Quantity = 4
;T18 Holesize 18. = 119.000000 Tolerance = +0.000000/-0.000000 NON_PLATED MILS Quantity = 8
;T19 Holesize 19. = 126.000000 Tolerance = +0.000000/-0.000000 NON_PLATED MILS Quantity = 2
;T20 Holesize 20. = 138.000000 Tolerance = +0.000000/-0.000000 NON_PLATED MILS Quantity = 1
;T21 Holesize 21. = 404.000000 Tolerance = +0.000000/-0.000000 NON_PLATED MILS Quantity = 2
%
G90
T01
X131200Y251181
Y703937
Y1156692
X379232
Y703937
Y251181
X627263
Y703937
Y1156692
X747244Y803149
Y370078
X961417Y692125
Y960629
X1181889
Y370078
X1301870Y251180
Y703937
Y1156692
X1549901
Y703937
Y251181
X1797933Y251180
Y703937
Y1156692
T02
X127988Y80319
Y76319
Y67319
Y71319
X134983Y52769
Y65269
Y61269
Y56769
X252200Y71319
Y67319
Y76319
Y80319
X259195Y65269
Y61269
Y56769
Y52769
X376413Y76319
Y71319
Y67319
Y80319
X383408Y61269
Y56769
Y52769
Y65269
X500625Y80319
Y76319
Y71319
Y67319
X507620Y56769
Y52769
Y61269
Y65269
X624838Y80319
Y76319
Y71319
Y67319
X631833Y65269
Y56769
Y52769
Y61269
X749051Y71319
Y76319
Y67319
Y80319
X756046Y61269
Y52769
Y56769
Y65269
X1252750Y53650
X1256750
X1261250
X1265250
X1266400Y68650
X1270400
X1275400
X1279400
X1376963Y53650
X1380963
X1385463
X1389463
X1390613Y68650
X1394613
X1399613
X1403613
X1501175Y53650
X1505175
X1509675
X1513675
X1514825Y68650
X1518825
X1523825
X1527825
X1625388Y53650
X1629388
X1633888
X1637888
X1639038Y68650
X1643038
X1648038
X1652038
X1749600Y53650
X1753600
X1758100
X1762100
X1763250Y68650
X1767250
X1772250
X1776250
X1873813Y53650
X1877813
X1882313
X1886313
X1887463Y68650
X1891463
X1896463
X1900463
Y521406
X1896463
X1891463
X1887463
X1886313Y506406
X1882313
X1877813
X1873813
X1776250Y521406
X1772250
X1767250
X1763250
X1762100Y506406
X1758100
X1753600
X1749600
X1652038Y521406
X1648038
X1643038
X1639038
X1637888Y506406
X1633888
X1629388
X1625388
X1527825Y521406
X1523825
X1518825
X1514825
X1513675Y506406
X1509675
X1505175
X1501175
X1403613Y521406
X1399613
X1394613
X1390613
X1389463Y506406
X1385463
X1380963
X1376963
X1279400Y521406
X1275400
X1270400
X1266400
X1265250Y506406
X1261250
X1256750
X1252750
X756046Y505525
Y509525
Y518025
Y514025
X749051Y520075
Y529075
Y533075
Y524075
X631833Y505525
Y518025
Y514025
Y509525
X624838Y533075
Y529075
Y520075
Y524075
X507620Y518025
Y505525
Y509525
Y514025
X500625Y529075
Y520075
Y524075
Y533075
X383408Y518025
Y509525
Y505525
Y514025
X376413Y529075
Y520075
Y533075
Y524075
X259195Y505525
Y509525
Y514025
Y518025
X252200Y524075
Y529075
Y520075
Y533075
X134983Y514025
Y505525
Y509525
Y518025
X127988Y533075
Y524075
Y529075
Y520075
X918400Y760750
X127988Y981831
Y976831
Y972831
Y985831
X134983Y966781
Y962281
Y958281
Y970781
X252200Y981831
Y976831
Y972831
Y985831
X259195Y966781
Y962281
Y970781
Y958281
X376413Y985831
Y976831
Y972831
Y981831
X383408Y970781
Y958281
Y966781
Y962281
X500625Y981831
Y976831
Y972831
Y985831
X507620Y966781
Y962281
Y958281
Y970781
X624838Y981831
Y976831
Y972831
Y985831
X631833Y970781
Y966781
Y962281
Y958281
X749051Y981831
Y976831
Y972831
Y985831
X756046Y966781
Y958281
Y970781
Y962281
X1257490Y970361
Y961861
Y957861
Y966361
X1273975Y976831
Y972831
Y981831
Y985831
X1381663Y961881
Y970381
Y966381
Y957881
X1398188Y972831
Y981831
Y985831
Y976831
X1505875Y966321
Y970321
Y957821
Y961821
X1522400Y981831
Y976831
Y972831
Y985831
X1630088Y962381
Y966881
Y970881
Y958381
X1646613Y981831
Y985831
Y976831
Y972831
X1754340Y970361
Y966361
Y961861
Y957861
X1770825Y976831
Y981831
Y985831
Y972831
X1878553Y966361
Y970361
Y961861
Y957861
X1895038Y985831
Y981831
Y976831
Y972831
X500000Y1472000
T03
X78000Y44000
X111437Y51319
X118437Y27697
X126900Y39500
X145864Y33216
X148050Y20971
X150700Y33100
X151200Y44400
Y48500
X157400Y35800
X157600Y24500
X157900Y17900
X175650Y28600
X185551Y21529
X198800Y34000
X203078Y33972
X217000Y38250
X235649Y51319
X242649Y27697
X262000Y30000
X338000Y44000
Y30000
X359862Y51319
X366862Y27697
X386000Y28000
X410679Y31098
X414000Y58000
X425500Y41250
X430500
X434804Y41242
X440400Y32400
X444663Y32417
X465500Y38250
X484074Y51319
X491074Y27697
X512000Y28000
X534000Y58000
X578000Y52000
X585500Y45000
X592500Y28000
X608287Y51319
X615287Y27697
X695600Y34000
X699932Y34034
X705171Y16254
X711352Y26875
X714000Y38250
X715205Y27012
X732500Y51319
X739500Y27697
X1261100Y16600
X1264700Y16400
X1282106Y51319
X1289106Y27697
X1298655Y59926
X1299800Y56000
X1303500Y35000
X1307200Y45000
X1308000Y35000
X1319100Y47400
X1406319Y51319
X1413319Y27697
X1431500Y48500
X1432000Y30000
X1435200Y58500
X1436000Y48500
X1468000Y42000
X1508000Y36000
X1530531Y51319
X1537531Y27697
X1549300Y56000
X1553000Y35000
X1556700Y45000
X1557500Y35000
X1574000Y26000
X1575400Y50750
X1594000Y56000
X1608000Y50000
X1632000Y26000
X1654744Y51319
X1661744Y27697
X1680000Y26000
Y48500
X1683700Y58500
X1684500Y48500
X1730000Y58000
X1756000Y25500
X1778956Y51319
X1785956Y27697
X1795600Y44900
X1803620Y57000
X1807500Y57400
X1811600Y32800
X1811700Y59550
X1814850Y21500
X1817500Y32700
X1821850Y35400
X1824200Y19000
Y23400
X1842400Y29500
X1859050Y19000
X1860500Y38100
X1863950Y45400
X1872900Y49000
X1878000Y29300
X1880500Y48900
X1884600Y49000
X1887900Y41300
X1891300Y49400
X1903169Y51319
X1910169Y27697
X1919000Y51000
X1903169Y81319
Y66319
X1898669Y103268
Y93819
Y84370
X1885508Y77413
X1885200Y81000
X1880500Y87000
X1875500
X1871400Y82000
X1870607Y75897
X1870500Y87000
X1868600Y68922
X1867600Y104300
X1865500Y87000
X1850800Y77200
X1845900Y77300
X1840900
X1823500Y113500
X1823300Y88600
X1820200Y70140
X1819134Y109132
X1819000Y113500
X1811300Y85600
X1808600Y78200
X1806300Y85600
X1803500Y82200
X1801300Y85600
X1799094Y82033
X1796300Y85600
X1794300Y63400
X1778956Y81319
Y66319
X1774456Y84370
Y103268
Y93819
X1763600Y119400
X1759600Y119500
X1746000Y106000
X1718000Y66000
X1707000Y103500
X1700400Y114100
X1699000Y61000
X1695400Y114100
X1692300Y96100
X1692200Y91200
Y86200
X1690400Y114100
X1686730Y80991
X1676300Y69500
X1672900Y76400
X1654744Y66319
Y81319
X1650244Y84370
Y103268
Y93819
X1639300Y119500
X1635300Y119600
X1608000Y62000
X1564000Y76500
X1559000
X1554000
X1549000
X1548500Y62900
X1548279Y69309
X1546000Y112000
X1530531Y81319
Y66319
X1526031Y84370
Y93819
Y103268
X1515400Y119400
X1511400Y119500
X1508500Y102500
X1494000Y98000
X1482000Y66000
X1474000Y78000
X1458500Y86500
Y101500
Y96500
Y91500
X1452000Y113500
X1450500Y61000
X1447000Y113500
X1442000
X1439500Y81000
X1435750Y73750
X1427800Y69500
X1422000Y98000
X1406319Y66319
Y81319
X1401819Y93819
Y103268
Y84370
X1394200Y113700
X1391200Y119500
X1358000Y91000
X1327000Y113500
X1326000Y92000
X1322500Y113500
X1317500
X1314500Y76500
X1309500
X1304500
X1299500
X1297000Y68500
X1282106Y81319
Y66319
X1278698Y84340
X1278038Y93821
X1266600Y119500
X1262600Y119700
X1262468Y103268
X747290Y118820
X732500Y66319
Y81319
X729201Y87285
X728000Y103268
X727636Y93834
X712214Y82500
X712000Y62940
X710000Y87500
X709000Y79500
X705000Y87500
X704000Y80500
X700300Y71700
X700000Y87500
X699500Y82500
X697787Y74488
X694500Y87500
X680500Y80250
X675500Y80000
X670500
X664500Y97000
X650000Y84000
X638000Y104000
X628000Y119500
X624000Y119400
X608287Y66319
Y81319
X603787Y93819
Y84370
Y103268
X590600Y64300
X589150Y69500
X589250Y80500
X586000Y87500
X583700Y80700
X581000Y87500
X579000Y105000
X576000Y87500
X572000Y73300
X571000Y87500
X561250Y98500
Y87500
X556000Y105500
X551500
X550250Y65500
X547000Y105500
X532000Y90000
X512000Y104000
X503900Y119500
X499900Y119400
X484074Y81319
Y66319
X479574Y93819
Y84370
Y103268
X468500Y80500
X467500Y116000
X464000Y80500
X462100Y62940
X461900Y91100
X456900
X454000Y83800
X451900Y91100
X450300Y71700
X446400Y91100
X440849Y111648
X440500Y72600
X435500
X430500
X425500
X402000Y64000
X379500Y119500
X375500Y119400
X359862Y81319
Y66319
X355362Y103268
Y93819
Y84370
X341800Y63700
X340750Y80500
X340650Y69300
X337500Y87500
X335200Y80700
X332500Y87500
X327500
X323500Y73300
X322500Y87500
X312750Y98500
X311800Y83700
X302999Y105501
X301750Y65500
X298500Y105500
X293700
X280000Y90000
X264000Y94000
X254900Y119600
X250900Y119500
X235649Y66319
Y81319
X231149Y103268
Y93819
X231000Y82000
X220000Y80500
X215500
X215100Y62940
X213000Y87500
X208000
X207000Y80500
X203300Y71700
X203000Y87500
X202500Y82500
X200819Y74819
X197500Y87500
X183500Y80250
Y75450
X178500Y80000
X154000Y106000
X144000Y88000
X131600Y119100
X127600Y119300
X111437Y66319
Y81319
X106937Y103268
Y84370
Y93819
X95800Y71800
X92500Y62800
X92250Y80500
X89000Y87500
X86700Y80700
X84000Y87500
X81500Y105000
X79000Y87500
X75000Y73300
X74000Y87500
X64250Y98500
Y87500
X59000Y105500
X56750Y62000
X54500Y105500
X50000
X38000Y86000
X30500Y67000
X48000Y160000
X49500Y140500
X72900Y133000
X73500Y120500
X89000Y162700
X111437Y151319
Y121319
Y131319
Y161319
X158000Y152000
X173500Y140500
X197000Y133000
X197500Y120500
X213500Y162700
X235649Y131319
Y151319
Y161319
Y121319
X256000Y142000
X284000Y160000
X298000Y140500
X321500Y133000
X322000Y120500
X337500Y162700
X357506Y123493
X359862Y151319
Y161319
Y131319
X394000Y164000
Y174000
X422000Y140500
X430083Y122357
X433500Y134500
X437500
X441300Y126000
X441500Y134500
X445500Y133000
X462000Y162700
X484074Y151319
Y121319
Y161319
Y131319
X502500Y139500
X544000Y160000
X546500Y140500
X556000Y156000
X569900Y133000
X570500Y120500
X586000Y162700
X608287Y131319
Y161319
Y151319
Y121319
X626000Y140000
X654000Y162500
X670500Y140500
X681000Y171500
X694200Y133000
X694500Y120500
X710300Y162700
X732500Y131319
Y151319
Y161319
Y121319
X753473Y138459
X1238000Y164000
X1256800Y132400
X1262000Y174000
X1282106Y151319
Y121319
Y161319
Y131319
X1302500Y152000
X1314000Y150500
X1346000Y179000
X1351500Y144500
X1376700Y136000
X1389000Y148500
X1392500Y173000
X1406319Y121319
Y161319
Y131319
Y151319
X1426500Y152000
X1438000Y150500
X1441100Y130800
X1484000Y158000
X1501300Y136100
X1526823Y161308
X1530531Y131319
Y151319
Y121319
X1547000Y156222
X1562500Y150500
X1593500Y160500
X1596400Y135600
Y126100
Y131100
X1625300Y136000
X1636000Y176000
X1653206Y134559
X1654744Y151319
Y121319
Y161319
X1675000Y152000
X1686500Y150500
X1730000Y136000
X1730500Y177500
X1749700Y135600
X1778956Y121319
Y151319
Y161319
Y131319
X1799000Y152000
X1811305Y147994
X1834018Y169783
X1841000Y140000
X1851500Y171500
X1860817Y120141
X1864800Y132500
X1881000Y162200
X1903169Y121319
Y161319
Y131319
Y151319
X1910169Y199941
X1883000Y181500
X1850000Y200000
X1840500Y237500
X1809500Y185500
X1804000Y205000
X1801500Y185500
X1795000
X1785956Y199941
X1754000Y234000
X1750000Y200000
X1724000Y232000
X1712525Y191268
X1685500Y185500
X1682000Y206000
X1677500Y185500
X1671003Y190635
X1661744Y199941
X1648000Y212000
X1616100Y203786
X1598000Y206000
X1592000Y236000
X1568000Y204000
X1561500Y185500
X1553500Y189500
X1547000Y185500
X1523100Y193700
X1502000Y196000
X1437000Y185500
X1429000
X1428000Y238000
X1422500Y185500
X1397937Y199951
X1388500Y230000
X1373000Y234500
X1338000Y225000
X1313000Y185500
X1307500Y205000
X1305000Y185500
X1298500
X1289106Y199941
X1272500Y213000
X1236500Y216000
X1089000Y217500
X732087Y207847
X716500Y186000
X700000Y200000
X652000Y214000
X615287Y199941
X592500Y186000
X568000Y190000
X534000Y222500
X493000Y218500
X491074Y199941
X468000Y186000
X416000Y196000
X388000
X366862Y199941
X344000Y186000
X324000Y196000
X242649Y199941
X219500Y186000
X212000Y236000
X198000Y198000
X174000Y236000
X118437Y199941
X95500Y186000
X88000Y204000
X76000Y232000
X50000Y200000
X250000Y250000
X288000Y242000
X582500Y266000
X586500Y292000
X714000Y240000
X771500Y251000
X802000Y263500
X1100000Y250000
X1150000
X1200000
X1394000Y249000
X1457500Y289000
X1508500Y292500
X1900000Y250000
Y300000
Y350000
X1829500Y311000
X1768000Y310000
X1715000Y305500
X1638500Y311500
X1550000Y350000
X1450000
X1400000
X1294624Y358802
X1294500Y331500
X1278500Y313000
X1252000Y358000
X1218000Y344000
X1200000Y300000
X1150000
X1100000
Y350000
X922700Y358100
X909423Y354393
X909236Y333242
X906616Y351586
X906486Y330524
X902184Y347219
X898059Y343029
X882823Y331182
X756000Y326000
X718000Y332000
X643000Y317500
X639000Y354500
X614500Y318500
X400000Y350000
X358000Y318000
X250000Y350000
Y300000
X214000Y328000
X162000Y310000
X150000Y350000
X112000Y316000
X38000Y348000
Y418000
X55209Y379278
X58728Y393206
X58709Y372346
X65692Y392187
X69942Y406555
X79581Y397946
X84581
X174000Y410000
X189342Y378932
X192842Y372000
X192861Y400482
X199825Y400700
X204075Y398609
X213214Y397600
X218214
X252564Y413509
Y417509
X257567Y409386
X261567
X266764Y413509
Y417509
X291042Y379232
X294542Y372300
X294561Y400682
X301525Y400900
X305775Y398909
X315514Y397600
X320514
X415542Y378932
X419042Y372000
X419061Y400382
X426025Y400700
X430275Y399351
X440014Y397600
X445014
X539742Y379232
X543242Y400682
Y372300
X550225Y400900
X554475Y399651
X564014Y397600
X569014
X602500Y365000
X650742Y378932
X654242Y372000
X654261Y400382
X661225Y400738
X665475Y399378
X680514Y397600
X685514
X704500Y408500
X804500Y379000
X850947Y417592
X860716Y417600
X908340Y360430
X910330Y363490
X922800Y362400
X945408Y378761
X950843Y378827
X1032924Y374988
X1033046Y379981
X1035000Y370500
X1098000Y378000
X1136000
X1144000Y418000
X1225600Y368700
X1243500Y393600
X1248500
X1259445Y379019
X1262945Y377600
X1262964Y400469
X1269926Y400687
X1274396Y407915
X1316000Y419000
X1337824Y379176
X1341343Y400626
X1341324Y372244
X1348305Y400844
X1352557Y399595
X1362514Y397100
X1367514
X1376000Y414000
X1388000Y378000
X1462036Y379176
X1465536Y372244
X1465555Y400626
X1472517Y400844
X1476769Y399595
X1487014Y397100
X1492014
X1586249Y379176
X1589749Y372244
X1589768Y400626
X1596730Y400844
X1600982Y399595
X1611014Y397100
X1616014
X1650000Y380000
X1714000Y391000
X1735014Y397100
X1740014
X1745737Y400643
X1749952Y405830
X1753631
X1759904Y400647
X1764168Y405501
X1781500Y366000
X1795433Y416927
X1800436Y412804
X1801642Y379532
X1804436Y412804
X1805142Y400982
Y372600
X1809633Y416927
X1812123Y401200
X1816375Y399951
X1827114Y397900
X1832114
X1838000Y415500
X1850000Y400000
X1900000
X1922400Y470400
X1900000Y450000
X1836476Y467034
X1834359Y473207
X1830359
X1830000Y424000
X1826359Y473207
X1822359
X1818359
X1814359
X1809633Y420927
X1795433
X1755159Y469723
X1746959Y459107
X1746859Y465707
X1742758Y456059
X1740906Y465239
X1731710Y475473
X1729596Y443182
Y447182
Y451182
Y459182
Y455182
X1725596Y447182
Y459182
Y443182
Y455182
Y451182
X1724096Y464344
X1724000Y422000
X1723896Y474582
X1721762Y454436
Y458436
X1717859Y463907
X1714026Y464191
X1711199Y453177
X1709496Y463382
X1708359Y449207
X1706859Y445207
X1696359Y452707
X1691859Y460207
X1689359Y452707
X1687359Y457207
X1681859Y452707
X1648000Y468000
X1604000Y432500
X1553500Y431500
X1484000Y432000
X1436500Y430000
X1378000
X1317500Y435500
X1281693Y473218
X1265295Y421223
X1257000Y434600
X1250648Y425686
X1247949Y423302
X1245959Y435527
X1245567Y420602
X1206000Y430500
X1201000Y447000
X1200500Y452000
X1190000Y466000
X1184000Y440000
X1160900Y468500
X1156110Y473330
X1152600Y468470
X1147440Y473040
X1143720Y468520
X1143420Y472900
X1139590Y468380
X1139330Y472820
X1136100Y460288
X1136000Y446849
X1135410Y468380
X1135310Y472820
X1131800Y446800
X1130800Y472900
X1119242Y477261
X1113593Y476094
X1103100Y457300
X1095100Y455800
X1092000Y448400
X1088000Y448500
X1038067Y441886
X1021890Y439717
X871591Y431161
X870400Y454315
X860519Y428234
X849539Y453596
X848799Y457202
X835165Y470414
X832417Y459017
X827361Y459317
X827313Y464805
X815255Y451343
X812282Y448094
X808395Y454315
X807500Y473700
X791971Y457721
Y461921
Y466121
X787971Y461921
Y466121
Y457721
X769500Y431500
X460000Y468000
X428000Y430000
X384000Y468000
X336000Y466000
X320000Y422000
X295090Y463289
X291590Y469789
X287590
X286000Y422000
X283590Y469789
X279590
X275590
X271590
X266690Y479089
X252490
X212390Y466305
X204190Y455689
X204090Y462289
X200022Y452941
X198137Y461821
X188941Y472055
X186827Y455764
Y451764
X182827Y447764
Y455764
Y439764
Y451764
Y443764
X181327Y460926
X181127Y471164
X178993Y455018
Y451018
X175090Y460489
X171257Y460773
X168430Y449759
X166727Y459964
X165590Y445789
X164127Y442264
X153590Y449289
X149090Y456789
X146590Y449289
X144590Y453789
X139090Y449289
X102000Y440000
X88000Y478000
X38000Y452000
X53250Y518000
X75000Y525800
X86700Y533200
X88000Y498000
X92250Y533000
X93800Y516800
X95500Y525500
X106937Y537126
X111437Y534075
Y519075
Y504075
X118437Y480453
X152000Y492000
X160000Y508000
X176439Y524992
X176506Y539295
X199000Y525800
X200090Y481289
X210700Y533200
X216000Y498000
X216250Y533000
X218000Y516600
X220000Y524000
X232433Y537126
X235649Y534075
Y504075
Y519075
X242649Y480453
X252490Y483089
X257687Y487212
X261687
X266690Y483089
X286000Y506000
Y490000
X301750Y518000
X312750Y536300
X323500Y525800
X335200Y533200
X338000Y498000
X340750Y533000
X341800Y516800
X344000Y525300
X355362Y537126
X359862Y504075
Y534075
Y519075
X366862Y480453
X392000Y490000
X429210Y512992
X436750Y538400
X446993Y527868
X459200Y533200
X460000Y496000
X464750Y533000
X464801Y521156
X466000Y516900
X479574Y537126
X483513Y535912
X484074Y504075
Y519075
X491074Y480453
X516000Y488000
X550250Y518000
X572000Y525800
X574000Y488000
X583550Y504600
X583700Y533200
X589250Y533000
X592500Y525300
X603787Y537126
X608287Y504075
Y519075
Y534075
X615287Y480453
X638000Y488000
X664651Y513000
X674250Y518000
X688000Y496000
X696000Y525800
X698600Y511100
X707700Y533200
X713250Y533000
X714600Y498100
X716400Y525200
X724600Y487100
X728000Y537126
X732500Y534075
Y504075
Y519075
X834000Y499000
X858740Y486430
X867299Y497200
Y493300
Y508600
Y504700
X873000Y494100
X873200Y487300
X922525Y519833
X929096Y517567
X935490Y519550
X935477Y524023
X938338Y529107
X944387Y520100
X956100Y516500
X962118Y534117
X965700Y519617
X971420Y537950
X975910Y537770
X984197Y533383
X986638Y519684
X991360Y529780
X991538Y522018
X995213Y529837
X996998Y539555
X998905Y529824
X1093000Y502000
X1102677Y487116
X1149964Y481623
X1150900Y485100
X1169000Y511500
X1177100Y495300
X1277606Y537126
X1282106Y519075
Y534075
Y504075
X1299900Y534200
X1300100Y530000
X1303800Y522500
X1307500Y501500
X1311200Y511500
X1312000Y501500
X1317500Y533500
X1325500Y504750
X1326500Y514000
X1327000Y487000
X1334500Y539500
X1345215Y533601
X1352000Y516000
X1364000Y492000
X1401819Y537126
X1406319Y504075
Y519075
Y534075
X1413319Y480453
X1424400Y534200
X1424500Y529100
X1427800Y522500
X1431500Y501500
X1432000Y482000
X1435200Y511500
X1436000Y501500
X1442500Y532000
X1449500Y504750
X1450500Y514000
X1458500Y539500
X1476000Y518000
X1510000Y488000
X1526031Y537126
X1530531Y519075
Y504075
Y534075
X1537531Y480453
X1548400Y528800
X1548600Y534900
X1552300Y522500
X1556000Y501500
X1558000Y482000
X1559700Y511500
X1560500Y501500
X1566500Y533000
X1574000Y504750
X1575000Y514000
X1583000Y539500
X1594000Y506000
X1604000Y536000
X1650244Y537126
X1654744Y519075
Y534075
Y504075
X1661744Y480453
X1673200Y535100
Y529000
X1676300Y522500
X1680000Y501500
X1682000Y484000
X1683700Y511500
X1684500Y501500
X1698000Y504750
X1699000Y514000
X1707083Y538435
X1720000Y506000
X1742859Y484707
X1767342Y533721
X1778956Y519075
Y504075
X1785728Y538736
X1785956Y480453
X1795359Y482507
Y486507
X1797400Y528800
X1798100Y537973
X1800300Y522500
X1800556Y490630
X1804000Y501500
X1804556Y490630
X1807700Y511500
X1808500Y501500
X1809559Y486507
Y482507
X1822000Y504750
X1823000Y514000
X1831000Y539500
X1839750Y530250
X1848500Y504000
X1853000
X1854000Y482000
X1859300Y524500
X1866500Y507250
X1866700Y512800
X1883200Y534600
X1883300Y530000
X1884000Y488000
X1898669Y537126
X1903169Y534075
Y519075
Y504075
X1910169Y480453
X1903169Y584075
Y574075
X1898669Y546575
Y556024
X1880500Y540500
X1875500
X1875000Y558000
X1870500Y540500
X1865500
X1865000Y573000
X1864700Y585500
X1855750Y551000
Y540000
X1850500Y558000
X1846000
X1841500
X1841000Y593000
X1831000Y549500
Y544500
Y554500
X1824500Y566500
X1819500
X1814500
X1813700Y548300
X1796000Y566500
X1778956Y574075
Y584075
X1774456Y546575
Y556024
X1759750Y576000
Y587000
X1757200Y558900
X1730000Y568000
X1728000Y554000
X1707083Y543435
X1706935Y548158
X1706800Y556300
X1700500Y566500
X1695500
X1690500
X1654744Y584075
X1652808Y574040
X1650244Y546575
Y556024
X1638200Y572200
X1634200
X1583000Y549500
Y554500
Y544500
X1576500Y566500
X1571500
X1570100Y583800
X1566500Y566500
X1530531Y574075
Y584075
X1526031Y546575
Y556024
X1515200Y572200
X1511200Y572300
X1498000Y586000
X1490000Y598000
X1480000Y546000
X1458500Y544500
Y554500
Y549500
X1452000Y566500
X1451800Y583800
X1447000Y566500
X1442000
X1406319Y584075
Y574075
X1401819Y546575
Y556024
X1394110Y575530
X1384000Y554000
X1383952Y573102
X1382000Y592000
X1334500Y554500
Y549500
Y544500
X1328000Y566500
X1323000
X1318000
X1298500Y562500
X1282106Y574075
Y584075
X1277606Y556024
Y546575
X1272182Y571361
X1272211Y575575
X1177350Y597792
X1172500Y599700
X1169125Y581776
X1167000Y586500
X1166550Y579200
X1138900Y584900
X1003591Y552081
X1000051Y547644
X990200Y544250
X988341Y563811
X985631Y559671
X974550Y563690
X974530Y559550
X968200Y547200
X955000Y540800
X941557Y547005
X938579Y551379
X938623Y556600
X752200Y572300
X748200Y572200
X732500Y584075
Y574075
X728000Y546575
Y556024
X716000Y568500
X710000Y540000
X705000
X700000
X695000
X694500Y573000
X694200Y585500
X688298Y551625
X685250Y540000
X680902Y557860
X676402
X672018Y557014
X670500Y593000
X644000Y558000
X637750Y575500
Y586250
X623005Y584047
X608287Y574075
X603787Y556024
Y546575
X586000Y540000
X581000
X576000
X571000
X569900Y585500
X565279Y578552
X561250Y551000
Y540000
X555321Y572375
X551276Y597925
X551044Y572149
X546500Y572000
X524000Y560000
X517999Y583015
X513250Y574252
X484074Y584075
Y574075
X479574Y556024
Y546575
X461500Y540000
X456500
X451500
X446500
X445546Y586021
X441641Y574141
X436750Y551000
X431500Y558000
X427000
X422500
X421820Y593641
X410000Y544000
X402000Y560000
X390632Y588624
X389250Y575500
X388000Y548000
X374261Y572963
X359862Y584075
X355362Y556024
Y546575
X337500Y540000
X332500
X327500
X323380Y589452
X322500Y540000
X322000Y573000
X312750Y551000
X308104Y556943
X303604
X299104
X298000Y593000
X278000Y554000
X268187Y578998
X268000Y544000
X264750Y586250
X235649Y584075
Y574075
X231149Y556024
Y546575
X213000Y540000
X212500Y557500
X208000Y540000
X203000
X198000
X197500Y573000
X197200Y585500
X188250Y540000
Y550951
X182300Y558600
X180500Y576000
X178100Y558600
X173600Y554400
Y558600
X173500Y593000
X156000Y544000
X144000Y550000
X143000Y587000
X140750Y575500
X130000Y560000
X111437Y584075
Y574075
X106937Y556024
Y546575
X89000Y540000
X84000
X81500Y557500
X79000Y540000
X74000
X73500Y573000
X72800Y585500
X64250Y540000
Y551000
X59000Y558000
X54500
X50000
X49500Y593000
X38000Y544000
X40000Y614000
X76000Y642000
X89000Y615200
X95500Y638500
X111437Y614075
Y604075
X118437Y652697
X162000Y614000
X200000Y646000
X213500Y615200
X219500Y638500
X235649Y604075
Y614075
X242649Y652697
X286000Y612000
X324000Y650000
X337500Y615200
X344000Y638500
X359862Y604075
Y614075
X366862Y652697
X410000Y616000
X467029Y610775
X468000Y638500
X483265Y606243
X484074Y614075
X491074Y652697
X510000Y656000
X516000Y637413
X536000Y644000
X586043Y615962
X592500Y638500
X615287Y652697
X622687Y614091
X622703Y604103
X671000Y648000
X672500Y615500
X710300Y615200
Y635400
X739500Y652697
X746356Y604075
X747843Y612115
X791530Y614700
X791680Y619050
X794883Y639984
X798475Y640227
X799900Y636300
X802900Y634000
X807440Y629910
X813980Y647430
X814320Y651120
X815148Y654937
X824618Y614617
X827750Y611798
X836862Y637500
X846950Y645820
Y640820
X860360Y605900
X863430Y618590
X867260Y608600
X870200Y631500
X878400Y626200
X878600Y615600
X878740Y647190
Y651190
Y643190
Y655190
X879600Y621600
X883030Y611940
X884801Y630225
X892400Y633700
X1083000Y620000
X1095000
X1112298Y618498
X1114905Y658882
X1118505Y658863
X1125025Y621993
X1129500Y619200
X1134600Y618747
X1171700Y603700
X1273979Y652690
X1282106Y604075
Y614075
X1298000Y638300
X1302500Y605000
X1305000Y638500
X1312973Y643128
X1314000Y603500
X1332000Y646000
X1358000Y600000
X1384000Y646000
X1406319Y604075
Y614075
X1413319Y652697
X1422500Y638500
X1426500Y605000
X1429000Y638500
X1437000
X1438000Y603500
X1460000Y646000
X1500000Y640000
X1530531Y614075
Y604075
X1537500Y656000
X1551000Y605000
X1553500Y638500
X1561500Y639860
X1562500Y603500
X1584000Y648000
X1632000
X1634000Y618000
X1654744Y614075
Y604075
X1661744Y652697
X1671000Y638500
X1675000Y605000
X1677500Y638500
X1685500
X1686500Y603500
X1706000Y646000
X1756000
X1762000Y628000
X1778956Y614075
Y604075
X1785956Y652697
X1795000Y638500
X1799000Y605000
X1801500Y638500
X1809500
X1810500Y603500
X1818000Y656000
X1850000Y650000
X1851400Y623800
X1880500Y615200
X1887000Y638500
X1903169Y604075
Y614075
X1910169Y652697
X1900000Y700000
X1846000Y686000
X1756000Y684000
X1700000Y700000
X1650000
X1602000Y684000
X1568000Y660000
X1382000Y688000
X1346000Y704000
X1318000Y660000
X1236690Y668490
Y664290
Y672690
X1232490Y685290
Y668490
Y672690
Y664290
Y681090
X1212587Y719895
X1210283Y695565
X1209931Y701608
X1207468Y697962
X1206414Y704261
X1179129Y672187
X1141230Y673825
X1112682Y681223
X1107674Y677776
X1103770Y675413
X1071179Y682315
X1067554Y694447
X1064216Y683751
X1059927Y688329
X1057826Y680233
X1056116Y697100
X859664Y683428
X837709Y681095
X822841Y662242
X796200Y682400
X791243Y668081
X789442Y681063
X788160Y666220
X726500Y681500
X709871Y686246
X693500Y680000
X666900Y665400
X646680Y679430
X590000Y680000
X552000Y686000
X454000
X422000Y684000
X334000Y686000
X250000Y700000
X174000Y686000
X38000Y660000
X92000Y758000
X156000Y768000
X250000Y750000
X342000Y758000
X466000Y762000
X542000Y764000
X600000Y770000
X650000
X710000Y760500
X712000Y720000
X718100Y738500
X718200Y744000
X723000Y739200
X723300Y743700
X728100Y745500
X728175Y741300
X778627Y735644
X778683Y745049
X791500Y764500
X795300Y764900
X810700Y776500
Y772000
X810659Y767500
X839400Y744920
X874500Y774500
Y779100
X874593Y763800
X874706Y752583
X874821Y767690
X874858Y757002
X903300Y763200
X903500Y769900
X903572Y773740
X905100Y777000
X910807Y766589
X932986Y752682
X936543Y762518
X963870Y754152
X966861Y772518
X971197Y775799
X1188000Y753500
X1190995Y776395
X1212587Y745095
Y740895
Y728295
Y749295
Y736695
Y732495
Y724095
X1254000Y748000
X1430000Y752000
X1508000Y748000
X1566000Y772000
X1650000Y750000
X1700000
X1758000Y748000
X1900000Y750000
Y800000
X1838174Y825000
X1834674Y831932
X1800000Y800000
X1713961Y825000
X1710461Y831932
X1591400Y825000
X1586249Y831932
X1465536Y825000
X1462036Y831932
X1384000Y782000
X1341324Y825000
X1337824Y832935
X1312000Y812000
X1278000Y810000
X1250000Y820000
X1217111Y825000
X1213611Y831932
X1186690Y791440
X1180520Y790880
X1180000Y832000
X1179690Y798020
X1177300Y804960
X1173990Y797760
X1050774Y815327
X1050650Y825420
X1042545Y832026
X1022838Y829101
X1015950Y838000
X1009950
X1005272Y837091
X1000827Y837072
X993400Y833250
X986471Y829716
X977676Y828513
X973070Y828512
X943294Y838833
X942500Y797867
X935485Y821400
X934800Y795300
X931800Y791500
X931380Y821500
X924484Y812558
X921047Y811463
X916855Y810934
X913059Y810367
X912762Y792801
X912030Y787650
X909144Y803346
X907800Y788700
X906166Y812784
X904484Y786109
X903700Y803200
X903221Y793938
X902560Y813313
X881702Y838859
X881216Y813813
X880983Y804420
X876255Y818998
X876256Y798895
X872600Y798700
X870001Y822862
X869989Y818847
X854973Y780437
X853900Y839200
X841800Y804499
X841309Y796644
X834200Y796220
X818162Y819005
X818113Y814998
X815469Y811029
X815330Y807050
X811372Y795900
X810700Y781000
X808372Y797900
X805372Y801700
X804200Y798200
X778735Y839888
X659642Y824700
X656142Y831632
X582648Y825223
X579148Y832411
X500000Y800000
X418742Y824444
X415242Y831882
X400000Y800000
X350000
X294542Y825000
X291042Y831932
X250000Y800000
X176558Y831000
X169442Y824700
X150000Y800000
X100000
X46442Y825000
X42942Y831932
X34000Y792000
X41263Y887025
X46461Y853382
X46763Y891525
X48763Y887025
X51263Y894525
X53425Y853600
X55763Y887025
X57675Y851609
X66263Y879525
X67763Y883525
X68526Y850100
X68900Y897700
X70603Y887495
X73430Y898509
X73526Y850100
X77263Y898225
X81166Y888754
Y892754
X83500Y898662
X85000Y877500
Y885500
Y893500
Y881500
Y889500
X89000
Y881500
Y893500
Y885500
Y877500
X100310Y899557
X102207Y890524
X106363Y893425
X113763Y865025
X154737Y850845
Y854845
X159740Y846722
X163740
X168937Y854845
Y850845
X172318Y844782
X176425Y853700
X180400Y852300
X191026Y850100
X196026
X250000Y850000
X294561Y853382
X301525Y853600
X305775Y851609
X315526Y850100
X320526
X350000Y850000
X418761Y853082
X425725Y853400
X429975Y851409
X440026Y850100
X445026
X500000Y850000
X564026Y850100
X569026
X582667Y853605
X589805Y854600
X594055Y852609
X624000Y846000
X659661Y853082
X666625Y853400
X670875Y851409
X673000Y885500
X677000
X680526Y850100
X685526
X701700Y872700
X714500Y870100
X723600Y872400
X727600Y872300
X754000Y884524
X757600Y884400
X815400Y892800
X817337Y886075
X819000Y896100
X820883Y879428
X820900Y888500
X825900Y862040
X826000Y857400
X833300Y856920
X844800Y895902
X845732Y891713
X848300Y847700
X858100Y850000
X858500Y845700
X861300Y895300
X866655Y855100
X870200Y852203
X876862Y842155
X877877Y891277
X879205Y873548
X879667Y877303
X879770Y868369
X883072Y886211
X884684Y877406
X890117Y865406
Y861206
X894317
Y865406
X911080Y857420
X915580
X920170Y857430
X924670
X928250Y885250
X930310Y858550
X931206Y845756
X934500Y885156
X939500Y842400
X940750Y886000
X944000Y842400
X948500
X953000
X957500
X958256Y894438
X962000Y842400
X964200Y855600
X969926Y847638
X972042Y884600
X974120Y858920
X976242Y884600
X980442Y882900
X985542
X986728Y891100
X989100Y899600
X989742Y882900
X993942
X997083Y895935
X1009600Y851054
X1014807Y899075
X1015007Y895000
X1025065Y896965
X1025251Y893000
X1025636Y854819
X1026932Y841614
X1028500Y879500
X1037110Y859471
X1039500Y891100
Y874700
X1044800Y893750
X1050082Y843729
X1058800Y893750
X1180000Y848000
X1180090Y896524
X1184750Y889200
Y896300
X1217089Y846182
X1224088Y844900
X1228344Y852351
X1247588Y842190
X1270000Y868000
X1310000Y860000
X1341343Y853382
X1348305Y853600
X1352557Y852351
X1362500Y851922
X1367500
X1400000Y850000
X1465555Y853382
X1472517Y853600
X1476769Y852351
X1487000Y851600
X1493500Y853100
X1550000Y850000
X1564000Y876000
X1589768Y853382
X1596730Y853600
X1597000Y857500
X1611000Y850100
X1616000
X1650000Y850000
X1713980Y853382
X1716000Y878000
X1720942Y853600
X1725194Y852351
X1735000Y850100
X1740000
X1756263Y887025
X1760000Y846000
X1761763Y891525
X1763763Y887025
X1766263Y894525
X1770763Y887025
X1781263Y879525
X1782763Y883525
X1783900Y897700
X1785603Y887495
X1788430Y898509
X1792263Y898225
X1796166Y888754
Y892754
X1798500Y898662
X1800000Y889500
Y877500
Y885500
Y881500
Y893500
X1804000Y885500
Y877500
Y881500
Y893500
Y889500
X1808000Y848000
X1815310Y899557
X1817739Y889758
X1821363Y893425
X1828763Y865025
X1838193Y853382
X1845155Y853600
X1849407Y852351
X1859500Y850100
X1864500
X1869537Y855445
Y851445
X1874540Y847322
X1878540
X1883737Y855445
Y851445
X1923600Y913525
X1914500Y902000
X1910169Y933209
X1908763Y907525
X1904763
X1903169Y956831
X1900763Y907525
X1896763
X1892763
X1888763
X1883663Y921025
Y917025
X1878660Y925148
X1874660
X1869463Y917025
Y921025
X1853000Y957000
X1848500Y940200
Y957000
X1829563Y904041
X1822000Y957250
X1821263Y900025
X1820700Y940600
X1817263Y919025
X1808500Y954000
X1806114Y909791
X1804000Y954000
X1798300Y908900
X1785956Y933209
X1778956Y956831
X1778500Y917500
X1738000Y904000
X1718000Y938000
X1709500Y900700
X1698000Y957250
X1690200Y937700
X1684500Y954000
X1680000
X1661800Y933400
X1654744Y956831
X1599000Y941000
X1579000Y940000
X1574000Y957250
X1572900Y902900
X1560500Y954000
X1556000
X1537531Y933209
X1530531Y956831
X1450100Y959500
X1443992Y904962
X1436000Y954000
X1431500
X1413319Y933209
X1406319Y956831
X1325500Y907000
Y957250
X1312000Y954000
X1307500
X1282106Y956831
X1274000Y933209
X1200407Y918060
X1200337Y912300
X1184778Y912848
X1181550Y906100
X1157556Y932754
X1141370Y905550
X1101600Y953700
X1087962Y959252
X1075706Y941261
X1046272Y944928
X1040200Y945000
X1034200
X1030862Y951946
X1027524Y948954
X1024129Y946152
X1012125Y925875
X996938Y901170
X927260Y922470
X922760
X918369Y923258
X914208Y924279
X909760Y925445
X889458Y907846
X842270Y936402
Y942411
X834470Y944430
X822463Y920345
X818434Y919985
X801300Y924300
X799303Y927296
X796301Y959795
X739500Y933209
X733895Y901054
X730900Y955800
X712760Y915137
X710000Y950500
X636000Y939000
X615287Y933209
X601904Y900960
X601800Y955500
X597904Y900960
X593904
X589904
X585904
X585000Y948000
X512000Y939000
X499800Y956831
X483549Y925564
X462000Y947000
X387500Y939000
X359500Y925400
X358800Y955900
X337500Y946500
X263500Y939500
X252100Y959100
X252000Y906000
X242649Y933209
X213500Y951500
X212000Y916000
X197263Y901025
X193763Y907525
X189763
X188000Y932000
X185763Y907525
X181763
X177763
X173763
X168863Y916425
Y920425
X163860Y924548
X159860
X154663Y920425
Y916425
X140000Y938000
X136000Y912000
X118437Y933209
X114563Y904041
X111437Y956831
X106263Y900025
X102263Y919025
X91114Y909791
X88000Y946000
X83300Y908900
X26000Y908000
Y940000
X38000Y996000
X50000Y1011000
X53250Y971000
X54500Y1011000
X59000
X64250Y993000
Y1004000
X74000Y993000
X75000Y978800
X79000Y993000
X81500Y1010500
X84000Y993000
X86700Y986200
X89000Y993000
X92250Y986000
X95500Y968000
Y972500
X106937Y999331
Y989882
Y1008780
X111437Y986831
Y971831
X125500Y992500
X142000Y1008000
X160000Y982000
X174500Y1011000
X178200Y977700
X179000Y1011000
X183500
X188750Y993000
Y1004000
X198500Y993000
X199500Y978800
X203500Y993000
X206000Y1010500
X208500Y993000
X211200Y986200
X213500Y993000
X216750Y986000
X218100Y969700
X220000Y978200
X231149Y989882
Y1008780
Y999331
X235649Y971831
Y986831
X252000Y992500
X265000Y1008500
X284500Y982000
X298500Y1011000
X302100Y978200
X303000Y1011000
X307500
X312750Y993000
Y1004000
X322500Y993000
X323500Y978800
X327500Y993000
X330000Y1010500
X332500Y993000
X335200Y986200
X337500Y993000
X340750Y986000
X341900Y969400
X344200Y978200
X355362Y989882
Y999331
Y1008780
X359862Y971831
Y986831
X376000Y993000
X389500Y1009000
X407000Y984000
X422500Y1011000
X426300Y976800
X427000Y1011000
X431500
X436750Y993000
Y1004000
X446500Y993000
X447500Y978800
X451500Y993000
X454000Y1010500
X456500Y993000
X459200Y986200
X461500Y993000
X464750Y986000
X466100Y969200
X468300Y978000
X479574Y989882
Y999331
Y1008780
X484074Y971831
Y986831
X500000Y992000
X513500Y1009000
X532000Y983000
X547000Y1011000
X550700Y979500
X551500Y1011000
X556000
X561250Y1004000
Y993000
X571000
X572000Y978800
X576000Y993000
X578000Y1010500
X581000Y993000
X583700Y986200
X586000Y993000
X589250Y986000
X590200Y969500
X592800Y978100
X603787Y1008780
Y989882
Y999331
X608287Y971831
Y986831
X624500Y993000
X625000Y1014500
X652500Y984500
X653500Y997500
X671000Y1011000
X675400Y980500
X675500Y1011000
X680000
X685250Y993000
Y1004000
X695000Y993000
X696000Y978800
X700000Y993000
X702500Y1010500
X705000Y993000
X707700Y986200
X710000Y993000
X713250Y986000
X714400Y969600
X716800Y978300
X728000Y1008780
Y999331
Y989882
X732500Y986831
Y971831
X755200Y992400
X759249Y1008800
X822470Y981470
X826000Y1004000
X826470Y981470
X827000Y985500
X834470Y981470
X839970
X846500Y997500
X848400Y974100
X886400Y976500
X888000Y980000
X890000Y976500
X891600Y980000
X893600Y976500
X895200Y980000
X897200Y976500
X1022080Y960728
X1093588Y972000
X1101950Y962900
X1104600Y967800
X1106000Y994000
X1108500Y960600
X1110600Y964200
X1130000Y994000
X1138000Y970000
X1252000Y1010000
X1260000Y993500
X1277606Y1008780
Y999331
Y989882
X1282106Y971831
Y986831
X1298000Y1014000
X1300600Y986800
X1300900Y981800
X1303800Y975000
X1311200Y964000
X1318000Y1019000
Y986000
X1323000Y1019000
X1326500Y966500
X1328000Y1019000
X1334500Y992000
Y997000
Y1002000
Y1007000
X1342000Y976000
X1356000Y998000
X1383200Y992700
X1401819Y989882
Y999331
Y1008780
X1406319Y986831
Y971831
X1424100Y987000
X1424400Y982000
X1427800Y975000
X1435200Y964000
X1442000Y1019000
X1442500Y984500
X1447000Y1019000
X1450500Y966500
X1452000Y1019000
X1458500Y1002000
Y997000
Y992000
Y1007000
X1478000Y976000
X1506000Y993000
X1526031Y999331
Y989882
Y1008780
X1530531Y986831
Y971831
X1544000Y1004500
X1548900Y987600
Y981500
X1552300Y975000
X1559700Y964000
X1566500Y985500
Y1019000
X1571500
X1575000Y966500
X1576500Y1019000
X1583000Y1002000
Y997000
Y992000
Y1007000
X1600500Y975000
X1612000Y980000
X1631500Y994000
X1650244Y999331
Y989882
Y1008780
X1654744Y971831
Y986831
X1668000Y1004000
X1672800Y981200
Y987300
X1676300Y975000
X1683700Y964000
X1690500Y986000
Y1019000
X1695500
X1699000Y966500
X1700500Y1019000
X1707000Y1007000
Y992000
Y997000
Y1002000
X1724000Y974000
X1728000Y1002000
X1756000Y993500
X1774456Y1008780
Y999331
Y989882
X1778956Y986831
Y971831
X1794500Y1007000
X1796900Y987200
Y981100
X1800300Y975000
X1807700Y964000
X1814500Y1019000
Y985500
X1819500Y1019000
X1823000Y966500
X1824500Y1019000
X1827600Y970700
X1831000Y992000
Y1007000
Y1002000
Y997000
X1839750Y983000
X1841500Y1011000
X1846000
X1850500
X1855750Y993000
Y1004000
X1859300Y977500
X1859600Y960250
X1865500Y993000
X1870800Y973100
X1871814Y993136
X1872500Y1010500
X1875800Y981000
X1876814Y993136
X1881814
X1883100Y984750
X1898669Y999331
Y989882
Y1008780
X1903169Y986831
Y971831
Y1056831
Y1066831
Y1036831
Y1026831
X1880500Y1068200
X1865000Y1026000
X1864500Y1038500
X1850000Y1078000
X1841000Y1046000
X1826000Y1036500
X1810500Y1056000
X1799000Y1057500
X1778956Y1026831
Y1066831
Y1056831
Y1036831
X1763300Y1024800
X1759300Y1024900
X1730000Y1050000
X1686500Y1056000
X1675000Y1057500
X1654744Y1026831
Y1066831
Y1056831
Y1036831
X1639100Y1024900
X1635100Y1024700
X1604000Y1022000
X1562500Y1056000
X1551000Y1057500
X1530531Y1056831
Y1066831
Y1026831
Y1036831
X1515400Y1025000
X1511400Y1024600
X1480000Y1020000
X1438000Y1056000
X1426500Y1057500
X1406319Y1056831
Y1066831
Y1036831
Y1026831
X1391000Y1024800
X1386900Y1024600
X1360000Y1054000
X1314000Y1056000
X1302500Y1057500
X1282106Y1036831
Y1026831
Y1066831
Y1056831
X1266400Y1024700
X1266000Y1046000
X1262400Y1024700
X1240000Y1070000
X1176000
X1155600Y1074500
X895500Y1038000
X846500Y1055000
X842700Y1071900
X836953Y1023500
X826000Y1062000
X753050Y1028500
X732500Y1066831
Y1026831
Y1056831
Y1036831
X710300Y1068200
X694500Y1026000
X694000Y1038500
X677000Y1028500
X670500Y1046000
X660000Y1068000
X637750Y1028500
X608287Y1056831
Y1066831
Y1026831
Y1036831
X586000Y1068200
X570500Y1026000
X569900Y1038500
X553000Y1028500
X546500Y1046000
X534000Y1068000
X513250Y1039250
Y1028500
X484074Y1066831
Y1056831
Y1036831
Y1026831
X462000Y1068200
X446000Y1026000
X445100Y1038500
X428500Y1028500
X422000Y1046000
X410000Y1068000
X389250Y1039250
Y1028500
X359862Y1026831
Y1066831
Y1056831
Y1036831
X337500Y1068200
X322000Y1026000
X321200Y1038500
X318000Y1058000
X304500Y1028500
X298000Y1046000
X288000Y1068000
X264450Y1039250
X264250Y1028500
X235649Y1036831
Y1026831
Y1056831
Y1066831
X213500Y1068200
X198000Y1026000
X197300Y1038500
X180500Y1028500
X174000Y1046000
X164000Y1068000
X140750Y1028500
Y1039250
X111437Y1066831
Y1056831
Y1026831
Y1036831
X89000Y1068200
X73500Y1026000
X72600Y1038400
X49500Y1046000
X50000Y1100000
X95500Y1091500
X118437Y1105453
X136500Y1111500
X200000Y1100000
X220000Y1091500
X242649Y1105453
X326000Y1106000
X344000Y1091500
X366862Y1105453
X448000Y1106000
X468000Y1091500
X491074Y1105453
X550000Y1100000
X592500Y1091500
X599000Y1115500
X615287Y1105453
X631500Y1112500
X698000Y1102000
X716500Y1091500
X739500Y1105453
X750000Y1084000
X759700Y1138600
X759762Y1135000
X826000Y1128000
Y1094000
X844000Y1128000
Y1092000
X943000Y1117500
X944500Y1134500
X947000Y1117500
X949500Y1114500
X951500Y1117500
X952500Y1134500
X954500Y1114500
X956500Y1117500
X960500Y1134500
X961000Y1117500
X965500Y1128000
X977643Y1132490
X982500Y1136500
X986500Y1131500
X1001687Y1111499
X1002671Y1124700
X1007431Y1122900
X1008739Y1096000
X1012800Y1122100
X1013231Y1089300
X1021970Y1096850
X1028500Y1118601
X1029000Y1122400
X1029500Y1104900
X1030178Y1134165
X1032361Y1114039
X1084000Y1092000
X1200000Y1100000
X1250000
X1264000Y1082000
X1266000Y1128000
X1289106Y1105453
X1298500Y1091000
X1305000
X1313000
X1350000Y1100000
X1413319Y1105453
X1422500Y1091000
X1429000
X1437000
X1500000Y1100000
X1537531Y1105453
X1547000Y1091000
X1553500
X1561500
X1600000Y1100000
X1638000Y1082000
X1661744Y1105453
X1671000Y1091000
X1677500
X1685500
X1696000Y1106000
X1762000Y1080000
X1785956Y1105453
X1795000Y1091000
X1801500
X1809500
X1887000Y1091500
X1910169Y1105453
X1918800Y1112100
X1900000Y1150000
X1850000
X1750000
X1700000
X1650000
X1600000
X1500000
X1450000
X1400000
X1350000
X1250000
X1200000
X1130000Y1154000
X1078000Y1166000
X1072931Y1191482
X1068569Y1191530
X1026100Y1145996
X1020000Y1153500
X1017500Y1150000
X1014500Y1153500
X1012000Y1150000
X982500Y1144500
Y1197000
X971700Y1193100
X964550Y1190200
X952500Y1193300
X947700Y1185500
X926700Y1199000
X904000Y1191700
X877400
X832800Y1147500
X821900Y1173700
X798920Y1150500
X795100Y1150400
X780722Y1166357
X780000Y1162800
X776800Y1169700
X773300Y1159700
X769800Y1156500
X748000Y1170000
X738000Y1152000
X700000Y1150000
X672000Y1146000
X670000Y1196000
X550000Y1150000
X500000
X450000
X300000
X250000
X200000
X50000
Y1200000
Y1250000
X100000
X200000Y1200000
X250000
X300000
X450000
X500000
X550000
X740000Y1202000
X746000Y1218000
X772601Y1214511
Y1219011
Y1223511
X777101
X782712Y1211404
Y1206904
X884677Y1219029
X885930Y1210537
X887200Y1216460
X888825Y1208263
X889965Y1213936
X890500Y1201200
X892460Y1211340
X893200Y1203660
X928500Y1220700
X943500Y1233000
X947500
X948298Y1215500
X951500Y1233000
X953000Y1203600
X953100Y1211400
X955500Y1233000
X957000Y1207500
X959500Y1233000
X960900Y1211400
Y1203600
X963500Y1233000
X967500
X982500Y1217000
Y1213000
Y1205000
Y1201000
Y1221000
Y1225000
Y1209000
X1020000Y1230000
X1072600Y1211400
X1072900Y1204500
X1080000Y1230000
X1084400Y1204200
X1084571Y1200129
X1178000Y1214000
X1200000Y1200000
X1250000
X1350000
X1400000
X1450000
X1500000
X1600000
X1650000
X1700000
X1750000
X1800000Y1250000
X1850000
Y1200000
X1900000Y1250000
Y1200000
Y1300000
X1850000
X1800000
X1676511Y1292495
X1650000Y1300000
X1600000
X1550000
X1500000
X1450000
X1288000Y1296000
X1274000Y1314000
X1238830Y1292533
X1235600Y1285803
X1230600
X1227100Y1292533
X1223730Y1285803
X1220450Y1292533
X1216894Y1318783
Y1308283
Y1304283
Y1314783
X1205624Y1292533
X1202394Y1285803
X1197394
X1193894Y1292533
X1190524Y1285803
X1185324Y1286563
X1183894Y1308783
Y1315783
Y1319783
Y1304783
X1133480Y1296700
Y1291700
X1126820Y1288500
X1123000Y1297600
X1121346Y1319676
Y1315676
Y1307385
Y1311385
X1100625Y1292025
X1096280Y1288150
X1092475Y1287971
X1083100Y1305600
X1082080Y1309495
Y1299375
X1078850Y1287900
X1072120Y1299375
Y1292460
Y1309495
Y1304495
X884056Y1283981
X871556
X859113Y1283983
X822500Y1294000
Y1298000
X522000Y1294000
X394086Y1313208
X389086
X384086
X379086
X374086
X373492Y1317441
X369086Y1313208
X364086
X359086
X354086
X349086
X344086
X343688Y1317736
X339086Y1313208
X334086
X329086
X324086
X319086
X313688Y1312736
Y1317736
X309086Y1313208
X304086
X299086
X294086
X227500Y1303000
X100000Y1300000
X50000
Y1350000
X100000
X250000
X293688Y1357736
X298688
X303688
X308688
X313688Y1322736
Y1357736
Y1337736
Y1332736
Y1347736
Y1342736
Y1352736
Y1327736
X318688Y1357736
X323688
X328688
X333688
X338688
X343688Y1352736
Y1357736
Y1347736
Y1332736
Y1342736
Y1337736
Y1322736
Y1327736
X348688Y1357736
X353688
X358688
X363688
X368688
X373492Y1352441
Y1342441
Y1347441
Y1337441
Y1327441
Y1332441
Y1322441
X373688Y1357736
X378688
X383688
X388688
X393688
X641102Y1321750
X646102
X822500Y1369500
Y1335000
Y1331000
Y1373500
X1054918Y1358239
Y1330439
Y1325739
Y1353539
X1075030Y1323078
X1099100Y1375200
Y1371200
X1099112Y1379273
X1105100Y1355000
Y1351000
X1107000Y1323500
X1114112Y1363273
X1117000Y1332500
Y1328500
X1118112Y1363273
X1122112
X1126112
X1130112
X1134112
X1138112
X1178712Y1372573
X1180614Y1340033
X1183894Y1346763
X1188894
X1193894
X1196000Y1366000
X1198894Y1346763
X1203394
X1208394
X1212000Y1366000
X1213820Y1340033
X1217100Y1346763
X1222000Y1346700
X1227100Y1346763
X1232100
X1236600
X1241600
X1243768Y1376953
X1246949Y1379513
X1274000Y1374000
X1450000Y1350000
X1500000
X1550000
X1600000
X1650000
X1800000
X1850000
X1900000
Y1400000
X1850000
X1760000Y1394000
X1735126Y1416300
X1719726Y1402700
X1716026Y1416500
X1702501Y1434000
X1694751
X1686226Y1432500
X1676626Y1432000
X1674000Y1410000
X1669376Y1429200
X1663906Y1428973
X1659906
X1651906
X1366000Y1388000
X1347400Y1416200
X1327900Y1416500
X1322000Y1430700
X1318540Y1424331
X1314375Y1424375
X1306625Y1434000
X1301534Y1431345
X1300000Y1388000
X1296374Y1430700
X1289124
X1281624Y1409209
X1277624
X1273874Y1423000
X1266914Y1394873
X1263642Y1392313
X1261224Y1387193
X1258187Y1389753
X1253165Y1384633
X1250347Y1382073
X1242000Y1412000
X1226000Y1436000
X1209819Y1417377
X1203312Y1402793
X1200962Y1413023
X1169412Y1396873
X1132112Y1380773
X1126112Y1401773
X1124612Y1388773
X1117362Y1406073
X1114000Y1430000
X1110512Y1403273
X1099112Y1391273
Y1383273
Y1387273
X1091000Y1393500
X1086646Y1396419
X1067712Y1384766
X1054918Y1381339
Y1386039
X1047000Y1421800
X1043606Y1437906
X1040127Y1422500
X1039900Y1417000
X1037400Y1400600
X1035943Y1424649
X1033287Y1410500
X1031443Y1426899
X1031400Y1399200
X1024193Y1422899
X1022818Y1393489
X1010943Y1413899
X1005943Y1406700
X1000443
X997443Y1436399
X996693Y1421399
X996443Y1406800
X992443Y1406700
X988693Y1421399
X988443Y1406700
X983943Y1407399
X979443Y1406999
X975443Y1407700
X966985Y1393900
X965443Y1436399
X964810Y1421172
X962136Y1431831
X961857Y1393900
X945414Y1412818
X945415Y1429318
X941559Y1403198
Y1408198
X926000Y1420000
X913935Y1402196
X901435
X888776Y1402228
X888000Y1424000
X876500Y1410843
X869937Y1400312
X866500Y1392892
X866000Y1398000
X860000Y1410843
X852000Y1406000
Y1402000
X842500Y1411343
X835000Y1402500
Y1398000
X750867Y1438001
X742880Y1422632
X739532Y1425934
X735232Y1439334
X724000Y1439700
X720455Y1438500
X703500Y1426000
X698500Y1418900
X693000Y1418800
X689250Y1433500
X689000Y1419000
X685000Y1418900
X681250Y1433500
X681000Y1419100
X676500Y1419500
X672000Y1419000
X668000Y1418900
X657836Y1433318
X646200Y1420576
X641200
X637971Y1425400
X528798Y1437733
X524722Y1436362
X523455Y1416564
X505224Y1424156
X390500Y1386000
X350000Y1400000
X300000
X209374Y1416300
X188274Y1416600
X175249Y1434075
X167499Y1434000
X165774Y1422700
X158484Y1416000
X156674Y1435085
X156374Y1430500
X149955Y1431573
X145274Y1434685
X139774Y1420600
X136774Y1411000
X131143Y1427661
X130601Y1411700
X130322Y1434014
X124074Y1437200
X100000Y1400000
X50000
X86000Y1444000
X104074Y1462500
X104184Y1457200
X105774Y1491000
X113314Y1441700
X114874Y1476700
X118574Y1465900
X120474Y1482800
X121274Y1447400
X124874Y1442600
X132674Y1484200
X135174Y1452400
X135374Y1445500
Y1464000
X137624Y1469000
X139374Y1486100
X145374Y1452500
X151874Y1449800
X157574Y1453500
X256000Y1466000
X259500Y1494000
X496500Y1476000
X503035Y1444331
X503001Y1454922
X504000Y1470500
X507250Y1478000
X508867Y1497771
X513624Y1458624
X523500Y1455400
X524236Y1463672
X528250Y1470900
X528500Y1444600
X532866Y1440238
X535200Y1466100
X537466Y1440238
X542066
X624750Y1461250
X628500Y1468500
X636250
X637972Y1441419
X650000Y1453552
Y1457448
Y1464052
Y1467948
X653000Y1488500
X658000Y1449200
Y1444000
X665700Y1468500
Y1453000
Y1458000
Y1463500
X675550Y1458721
Y1452216
X679800Y1483500
X680200Y1465500
X680900Y1469200
X684000Y1482000
X685000Y1453500
X685850Y1468600
X690000Y1453500
Y1458500
Y1448500
X692000Y1471156
X695000Y1453500
X699500Y1476000
X708600Y1469900
X717600Y1449700
X718900Y1472800
X722200Y1476900
X724066Y1461018
X724248Y1465560
X724255Y1457253
X730341Y1446725
X730500Y1451500
X732232Y1477094
X735232Y1451210
X739332Y1462234
X745032Y1468534
X745000Y1463000
X746832Y1451034
X756332Y1465934
X772361Y1451972
X820000Y1448000
X866000Y1452000
X900000Y1450000
X944019Y1452220
X961877Y1441451
Y1445347
X982343Y1446620
Y1440115
X987576Y1451454
Y1455054
X992443Y1441399
X993100Y1456550
X993830Y1471364
X997443Y1446399
Y1441399
X998325Y1471434
X999443Y1458006
X1002118Y1471365
X1002443Y1441399
X1007618Y1477365
X1013418Y1470865
X1017618Y1460865
Y1470865
X1021693Y1444649
X1021818Y1470865
X1024175Y1482189
X1027288Y1467441
X1033253Y1444649
X1035526Y1455899
X1037550Y1475814
X1038303Y1441709
X1041176Y1455500
X1048553Y1448399
X1049260Y1466691
X1130873Y1495848
Y1490848
X1156000Y1494000
X1190000
X1200000Y1450000
X1238000Y1444000
X1252674Y1496800
X1253374Y1459300
Y1470000
X1256474Y1446000
X1260574Y1445600
X1260874Y1481400
X1264774Y1470700
X1266474Y1487500
X1266574Y1452300
X1278574Y1488700
X1282374Y1445500
Y1464000
X1284624Y1476400
X1289574Y1483700
X1292374Y1452500
X1297089Y1450307
X1303874Y1453750
X1406000Y1444000
X1450000Y1450000
X1500000
X1550000
X1600000
X1656250Y1461250
X1661626Y1480000
X1662626Y1464000
Y1445500
X1672626Y1452500
X1674926Y1447400
X1683926Y1453750
X1790226Y1469300
Y1458600
X1794226Y1473300
X1794426Y1446400
X1800326Y1445800
X1803426Y1452600
X1804326Y1480500
X1810426Y1476200
X1822000Y1444000
X1822326Y1481600
X1824826Y1470900
X1878000Y1484000
X1900000Y1450000
X1904000Y1504000
X1034100Y1500564
X1020500Y1500014
T04
X826700Y258531
X841000
X855100
X869300
X1137600Y527100
X1137446Y541317
Y555490
Y569663
Y698798
Y712971
Y727144
Y741317
Y755490
Y769663
Y783836
Y798010
Y812183
Y826356
Y840529
Y854703
Y868876
Y883049
Y897222
Y911396
Y925569
Y939742
T05
X833859Y253937
Y258268
X848032
Y253937
X862205Y258268
Y253937
X876378Y258268
Y253937
X897638
Y258268
X911811
Y253937
Y263779
Y268110
X904725Y268504
Y262992
X897638Y263779
Y268110
X890552Y262992
Y268504
X876378Y268110
Y263779
X869292Y262992
Y268504
X862205Y268110
Y263779
X855118Y262992
Y268504
X848032Y263779
Y268110
X840945Y262992
Y268504
X833859Y268110
Y263779
X826772Y262992
Y268504
Y272835
Y277165
X833859Y272441
Y277953
X840945Y272835
Y277165
X848032Y277953
Y272441
X855118Y277165
Y272835
X862205Y272441
Y277953
X869292Y277165
Y272835
X876378Y272441
Y277953
X890552Y272835
Y277165
X897638Y272441
Y277953
X904725Y272835
Y277165
X911811Y272441
Y277953
Y282283
Y286614
X904725Y287008
Y282677
X897638Y286614
Y282283
X890552Y282677
Y287008
X876378Y282283
Y286614
X869292Y282677
Y287008
X862205Y282283
Y286614
X855118Y282677
Y287008
X848032Y282283
Y286614
X840945Y287008
Y282677
X833859Y286614
Y282283
X826772Y282677
Y287008
Y291338
Y296850
X833859Y292126
Y296457
X840945Y296850
Y291338
X848032Y292126
Y296457
X855118Y291338
Y296850
X862205Y292126
Y296457
X869292Y291338
Y296850
X876378Y296457
Y292126
X890552Y291338
Y296850
X897638Y296457
Y292126
X904725Y291338
Y296850
X911811Y296457
Y292126
Y306299
Y300787
X904725Y305512
Y301181
X897638Y300787
Y306299
X890552Y301181
Y305512
X876378Y300787
Y306299
X869292Y305512
Y301181
X862205Y306299
Y300787
X855118Y305512
Y301181
X848032Y306299
Y300787
X840945Y301181
Y305512
X833859Y300787
Y306299
X826772Y305512
Y301181
Y315354
Y311023
X833859Y310630
X840945Y311023
Y315354
X848032Y310630
X855118Y311023
Y315354
X862205Y310630
X869292Y311023
Y315354
X876378Y310630
X890552Y315354
Y311023
X897638Y310630
X904725Y311023
Y315354
X911811Y310630
X1091089Y520057
X1095026Y527143
X1095420Y520057
X1099357Y527143
X1100932Y520057
X1104869Y527143
X1105262Y520057
X1109199Y527143
X1109593Y520057
X1113530Y527143
X1115105Y520057
X1119042Y527143
X1119435Y520057
X1123372Y527143
X1123766Y520057
X1127703Y527143
X1129278Y520057
X1133215Y527143
X1133609Y520057
Y534230
X1129278
X1123766
X1119435
X1115105
X1109593
X1105262
X1100932
X1095420
X1091089
Y548403
X1095026Y541317
X1095420Y548403
X1099357Y541317
X1100932Y548403
X1104869Y541317
X1105262Y548403
X1109199Y541317
X1109593Y548403
X1113530Y541317
X1115105Y548403
X1119042Y541317
X1119435Y548403
X1123372Y541317
X1123766Y548403
X1127703Y541317
X1129278Y548403
X1133215Y541317
X1133609Y548403
X1133215Y555490
X1127703
X1123372
X1119042
X1113530
X1109199
X1104869
X1099357
X1095026
X1091089Y562576
X1095026Y569663
X1095420Y562576
X1099357Y569663
X1100932Y562576
X1104869Y569663
X1105262Y562576
X1109199Y569663
X1109593Y562576
X1113530Y569663
X1115105Y562576
X1119042Y569663
X1119435Y562576
X1123372Y569663
X1123766Y562576
X1127703Y569663
X1129278Y562576
X1133215Y569663
X1133609Y562576
Y691711
X1133215Y698797
X1129278Y691711
X1127703Y698797
X1123766Y691711
X1123372Y698797
X1119435Y691711
X1119042Y698797
X1115105Y691711
X1113530Y698797
X1109593Y691711
X1109199Y698797
X1105262Y691711
X1104869Y698797
X1100932Y691711
X1099357Y698797
X1095420Y691711
X1095026Y698797
X1091089Y691711
Y705884
X1095420
X1100932
X1105262
X1109593
X1115105
X1119435
X1123766
X1129278
X1133609
X1133215Y712970
X1127703
X1123372
X1119042
X1113530
X1109199
X1104869
X1099357
X1095026
X1091089Y720057
X1095026Y727144
X1095420Y720057
X1099357Y727144
X1100932Y720057
X1104869Y727144
X1105262Y720057
X1109199Y727144
X1109593Y720057
X1113530Y727144
X1115105Y720057
X1119042Y727144
X1119435Y720057
X1123372Y727144
X1123766Y720057
X1127703Y727144
X1129278Y720057
X1133215Y727144
X1133609Y720057
Y734230
X1129278
X1123766
X1119435
X1115105
X1109593
X1105262
X1100932
X1095420
X1091089
Y748403
X1095026Y741317
X1095420Y748403
X1099357Y741317
X1100932Y748403
X1104869Y741317
X1105262Y748403
X1109199Y741317
X1109593Y748403
X1113530Y741317
X1115105Y748403
X1119042Y741317
X1119435Y748403
X1123372Y741317
X1123766Y748403
X1127703Y741317
X1129278Y748403
X1133215Y741317
X1133609Y748403
X1133215Y755490
X1127703
X1123372
X1119042
X1113530
X1109199
X1104869
X1099357
X1095026
X1091089Y762577
X1095026Y769663
X1095420Y762577
X1099357Y769663
X1100932Y762577
X1104869Y769663
X1105262Y762577
X1109199Y769663
X1109593Y762577
X1113530Y769663
X1115105Y762577
X1119042Y769663
X1119435Y762577
X1123372Y769663
X1123766Y762577
X1127703Y769663
X1129278Y762577
X1133215Y769663
X1133609Y762577
Y776750
X1129278
X1123766
X1119435
X1115105
X1109593
X1105262
X1100932
X1095420
X1091089
X1095026Y783836
X1099357
X1104869
X1109199
X1113530
X1119042
X1123372
X1127703
X1133215
X1133609Y790923
X1133215Y798010
X1129278Y790923
X1127703Y798010
X1123766Y790923
X1123372Y798010
X1119435Y790923
X1119042Y798010
X1115105Y790923
X1113530Y798010
X1109593Y790923
X1109199Y798010
X1105262Y790923
X1104869Y798010
X1100932Y790923
X1099357Y798010
X1095420Y790923
X1095026Y798010
X1091089Y790923
Y805096
X1095420
X1100932
X1105262
X1109593
X1115105
X1119435
X1123766
X1129278
X1133609
Y819270
X1133215Y812183
X1129278Y819270
X1127703Y812183
X1123766Y819270
X1123372Y812183
X1119435Y819270
X1119042Y812183
X1115105Y819270
X1113530Y812183
X1109593Y819270
X1109199Y812183
X1105262Y819270
X1104869Y812183
X1100932Y819270
X1099357Y812183
X1095420Y819270
X1095026Y812183
X1091089Y819270
X1095026Y826356
X1099357
X1104869
X1109199
X1113530
X1119042
X1123372
X1127703
X1133215
X1133609Y833443
X1129278
X1123766
X1119435
X1115105
X1109593
X1105262
X1100932
X1095420
X1091089
Y847616
X1095026Y840529
X1095420Y847616
X1099357Y840529
X1100932Y847616
X1104869Y840529
X1105262Y847616
X1109199Y840529
X1109593Y847616
X1113530Y840529
X1115105Y847616
X1119042Y840529
X1119435Y847616
X1123372Y840529
X1123766Y847616
X1127703Y840529
X1129278Y847616
X1133215Y840529
X1133609Y847616
X1133215Y854703
X1127703
X1123372
X1119042
X1113530
X1109199
X1104869
X1099357
X1095026
X1091089Y861789
X1095026Y868876
X1095420Y861789
X1099357Y868876
X1100932Y861789
X1104869Y868876
X1105262Y861789
X1109199Y868876
X1109593Y861789
X1113530Y868876
X1115105Y861789
X1119042Y868876
X1119435Y861789
X1123372Y868876
X1123766Y861789
X1127703Y868876
X1129278Y861789
X1133215Y868876
X1133609Y861789
Y875962
X1129278
X1123766
X1119435
X1115105
X1109593
X1105262
X1100932
X1095420
X1091089
X1095026Y883049
X1099357
X1104869
X1109199
X1113530
X1119042
X1123372
X1127703
X1133215
X1133609Y890136
X1133215Y897222
X1129278Y890136
X1127703Y897222
X1123766Y890136
X1123372Y897222
X1119435Y890136
X1119042Y897222
X1115105Y890136
X1113530Y897222
X1109593Y890136
X1109199Y897222
X1105262Y890136
X1104869Y897222
X1100932Y890136
X1099357Y897222
X1095420Y890136
X1095026Y897222
X1091089Y890136
Y904309
X1095420
X1100932
X1105262
X1109593
X1115105
X1119435
X1123766
X1129278
X1133609
Y918482
X1133215Y911396
X1129278Y918482
X1127703Y911396
X1123766Y918482
X1123372Y911396
X1119435Y918482
X1119042Y911396
X1115105Y918482
X1113530Y911396
X1109593Y918482
X1109199Y911396
X1105262Y918482
X1104869Y911396
X1100932Y918482
X1099357Y911396
X1095420Y918482
X1095026Y911396
X1091089Y918482
X1095026Y925569
X1099357
X1104869
X1109199
X1113530
X1119042
X1123372
X1127703
X1133215
X1133609Y932655
X1133215Y939742
X1129278Y932655
X1127703Y939742
X1123766Y932655
X1123372Y939742
X1119435Y932655
X1119042Y939742
X1115105Y932655
X1113530Y939742
X1109593Y932655
X1109199Y939742
X1105262Y932655
X1104869Y939742
X1100932Y932655
X1099357Y939742
X1095420Y932655
X1095026Y939742
X1091089Y932655
T06
X40412Y6000
X35412
X30412
X25412
X95412
X20412
X10412
X45412
X15412
X90412
X85412
X80412
X75412
X70412
X65412
X60412
X55412
X50412
X6000Y6588
Y11588
Y16588
Y21588
Y26588
Y31588
Y36588
Y41588
Y46588
Y51588
Y56588
Y61588
Y66588
Y71588
Y76588
Y81588
Y86588
Y91588
Y96588
Y101588
Y106588
Y111588
Y116588
Y121588
Y126588
Y131588
Y136588
Y141588
Y146588
Y151588
Y156588
Y161588
Y166588
Y171588
Y176588
Y181588
Y186588
Y191588
Y196588
Y201588
Y206588
Y211588
Y216588
Y221588
Y226588
Y231588
Y236588
Y241588
Y246588
Y251588
Y256588
Y261588
Y266588
Y271588
Y276588
Y281588
Y286588
Y291588
Y296588
Y301588
Y306588
Y311588
Y316588
Y321588
Y326588
Y331588
Y336588
Y341588
Y346588
Y351588
Y356588
Y361588
Y366588
Y371588
Y376588
Y381588
Y386588
Y391588
Y396588
Y401588
Y406588
Y411588
Y416588
Y421588
Y426588
Y431588
Y436588
Y441588
Y446588
Y451588
Y456588
Y461588
Y466588
Y471588
Y476588
Y481588
Y486588
Y491588
Y496588
Y501588
Y506588
Y511588
Y516588
Y521588
Y526588
Y531588
Y536588
Y541588
Y546588
Y551588
Y556588
Y561588
Y566588
Y571588
Y576588
Y581588
Y586588
Y591588
Y596588
Y601588
Y606588
Y611588
Y616588
Y621588
Y626588
Y631588
Y636588
Y641588
Y646588
Y651588
Y656588
Y661588
Y666588
Y671588
Y676588
Y681588
Y686588
Y691588
Y696588
Y701588
Y706588
Y711588
Y716588
Y721588
Y726588
Y731588
Y736588
Y741588
Y746588
Y751588
Y756588
Y761588
Y766588
Y771588
Y776588
Y781588
Y786588
Y791588
Y796588
Y801588
Y806588
Y811588
Y816588
Y821588
Y826588
Y831588
Y836588
Y841588
Y846588
Y851588
Y856588
Y861588
X21500Y864100
X26300
X6000Y866588
X21500Y868900
X26300
X6000Y871588
X21500Y873700
X26300
X6000Y876588
Y881588
Y886588
Y891588
Y896588
Y901588
Y906588
Y911588
Y916588
Y921588
Y926588
Y931588
Y936588
Y941588
Y946588
Y951588
Y956588
Y961588
Y966588
Y971588
Y976588
Y981588
Y986588
Y991588
Y996588
Y1001588
Y1006588
Y1011588
Y1016588
Y1021588
Y1026588
Y1031588
Y1036588
Y1041588
Y1046588
Y1051588
Y1056588
Y1061588
Y1066588
Y1071588
Y1076588
Y1081588
Y1086588
Y1091588
Y1096588
Y1101588
Y1106588
Y1111588
Y1116588
Y1121588
Y1126588
Y1131588
Y1136588
Y1141588
Y1146588
Y1151588
Y1156588
Y1161588
Y1166588
Y1171588
Y1176588
Y1181588
Y1186588
Y1191588
Y1196588
Y1201588
Y1206588
Y1211588
Y1216588
Y1221588
Y1226588
Y1231588
Y1236588
Y1241588
Y1246588
Y1251588
Y1256588
Y1261588
Y1266588
Y1271588
Y1276588
Y1281588
Y1286588
Y1291588
Y1296588
Y1301588
Y1306588
Y1311588
Y1316588
Y1321588
Y1326588
Y1331588
Y1336588
Y1341588
Y1346588
Y1351588
Y1356588
Y1361588
Y1366588
Y1371588
Y1376588
Y1381588
Y1386588
Y1391588
Y1396588
Y1401588
Y1406588
Y1411588
Y1416588
Y1421588
Y1426588
Y1431588
Y1436588
Y1441588
Y1446588
Y1451588
X11000Y1455500
X15500Y1458500
X17811Y1462693
Y1467693
Y1472693
Y1477693
Y1482693
Y1487693
Y1492693
Y1497693
X77539Y1499118
X72539
X87539
X67539
X92539
X82539
X99000Y1501000
X61500Y1502000
X17811Y1502693
Y1507693
X58500Y1508000
X17500Y1512000
X51819Y1513685
X46819
X31819
X36819
X26819
X21819
X56819
X41819
X187433
X127433
X152433
X107433
X112433
X117433
X122433
X132433
X137433
X142433
X147433
X177433
X182433
X172433
X157433
X162433
X167433
X197433
X192433
X103000Y1511000
X102000Y1505500
X186000Y1430000
X180000
Y1424000
X186000
X170000Y1383000
X152000
X164000
X158000
Y1377000
X170000
X152000
X164000
X169215Y895685
X154215
Y890885
X169215
X183363Y888625
X197763
X192963
X173763
X188163
X178563
X158900Y885700
X164200
X113363Y884925
X173763Y883625
X183363
X188163
X197763
X192963
X178563
X154215Y880885
X169215
X154215Y876085
X169215
X122800Y437500
X127600
Y432700
X122800
X127600Y427900
X122800
X120412Y6000
X125412
X130412
X135412
X140412
X145412
X150412
X155412
X115412
X110412
X105412
X100412
X175412
X170412
X195412
X190412
X160412
X185412
X165412
X180412
X260412
X255412
X250412
X245412
X240412
X235412
X270412
X265412
X230412
X225412
X220412
X215412
X210412
X205412
X200412
X295412
X290412
X285412
X280412
X275412
X211590Y427289
X251200Y438300
X267752Y438560
X251200Y443100
X267752Y443360
X277100Y446100
X281900
X286700
X291500
X296300
X272300
X211190Y447189
X261927Y448364
X257127
X296300Y451100
X291500
X286700
X277100
X281900
X272300
X251200Y453100
X267752Y453360
X251200Y457900
X267752Y458160
X237235Y1419039
X236974Y1425000
X233074Y1429500
X239274Y1429600
X298685Y1490063
X288685
X293685
X283000Y1492000
X279000Y1498500
X278646Y1504398
Y1509398
X262433Y1513685
X202433
X207433
X252433
X212433
X247433
X277433
X267433
X242433
X272433
X257433
X217433
X222433
X227433
X232433
X237433
X333685Y1490063
X328685
X323685
X318685
X313685
X308685
X303685
X373685
X368685
X363685
X338685
X383685
X388685
X393685
X398685
X378685
X343685
X358685
X353685
X348685
X374780Y1434599
X380780
X374780Y1428599
X380780
Y1422599
X374780
X380780Y1416599
X374780
X380780Y1410599
X374780
X395412Y6000
X370412
X365412
X360412
X355412
X350412
X380412
X385412
X390412
X300412
X305412
X375412
X325412
X320412
X310412
X315412
X345412
X340412
X335412
X330412
X410412
X415412
X420412
X450412
X430412
X435412
X400412
X405412
X440412
X445412
X455412
X460412
X465412
X470412
X475412
X480412
X485412
X490412
X425412
X495412
X478685Y1490063
X403685
X408685
X413685
X418685
X488685
X423685
X483685
X428685
X433685
X438685
X443685
X448685
X453685
X458685
X463685
X468685
X473685
X494500Y1490500
X529937Y1513685
X594937
X599937
X519937
X524937
X534937
X514937
X589937
X584937
X579937
X574937
X569937
X504937
X564937
X544937
X539937
X559937
X554937
X549937
X509937
X503244Y1509378
Y1504378
X503000Y1499000
X501000Y1494000
X513917Y1447297
X519717
X507917
X595412Y6000
X590412
X585412
X580412
X525412
X575412
X570412
X565412
X560412
X555412
X550412
X545412
X515412
X540412
X520412
X535412
X530412
X500412
X505412
X510412
X680412
X675412
X645412
X640412
X650412
X690412
X635412
X685412
X600412
X605412
X670412
X665412
X660412
X655412
X610412
X615412
X630412
X620412
X625412
X695412
X693012Y1499118
X698012
X688012
X680500Y1503500
X678500Y1510500
X669937Y1513685
X664937
X634937
X674937
X659937
X654937
X649937
X644937
X639937
X604937
X609937
X614937
X619937
X624937
X629937
X770551
X765551
X755551
X760551
X725551
X730551
X750551
X735551
X740551
X745551
X773528Y1510662
X724000Y1509500
X773528Y1505662
X722000Y1503500
X773528Y1500662
X718500Y1500000
X708012Y1499118
X713012
X703012
X775000Y1495500
X779500Y1491000
X786803Y1490063
X791803
X796803
X789300Y1227168
X794100
X789300Y1222368
X794100
X789300Y1217568
X794100
Y1206900
X789300
X794100Y1202100
X789300
Y1197300
X794100
X798400Y587268
Y582468
Y577668
Y567000
Y562200
Y557400
X790522Y195764
X795522
X784022Y194764
X779022Y190764
X777465Y183947
Y178947
Y173947
Y168947
Y163947
Y158947
Y153947
Y148947
Y143947
Y138947
Y133947
Y128947
Y123947
Y118947
Y113947
Y108947
Y103947
Y98947
Y93947
Y88947
Y83947
Y78947
Y73947
Y68947
Y63947
Y58947
Y53947
Y48947
Y43947
Y38947
Y33947
Y28947
Y23947
Y18947
Y13947
X778000Y9500
X710412Y6000
X715412
X700412
X705412
X775412
X770412
X760412
X755412
X720412
X765412
X750412
X745412
X740412
X735412
X730412
X725412
X805522Y195764
X800522
X809500Y197500
X808961Y201678
Y206678
Y211678
Y216678
Y221678
Y226678
Y231678
Y236678
Y241678
X887127Y254031
X802843Y399396
X807643
X826843Y399496
X822043
X807643Y404196
X802843
X822043Y404296
X826843
X807643Y408996
X802843
X822043Y409096
X826843
X807643Y419664
X802843
X822043Y419764
X826843
X802843Y424464
X807643
X826843Y424564
X822043
X807643Y429264
X802843
X822043Y429364
X826843
X803200Y557400
X822400Y557500
X817600
X803200Y562200
X822400Y562300
X817600
X803200Y567000
X817600Y567100
X822400
X803200Y577668
X822400Y577768
X817600
X803200Y582468
X817600Y582568
X822400
X803200Y587268
X817600Y587368
X822400
X813100Y1197300
X808300
X813100Y1202100
X808300
Y1206900
X813100
X808300Y1217568
X813100
X808300Y1222368
X813100
X808300Y1227168
X813100
X801803Y1490063
X831803
X816803
X806803
X836803
X841803
X846803
X821803
X811803
X896803
X891803
X881803
X851803
X856803
X861803
X866803
X871803
X876803
X826803
X886803
X944200Y1083100
X938900Y1103700
X938800Y1109300
X945200Y1393500
X950200Y1394500
X945200Y1398300
X976803Y1490063
X906803
X951803
X946803
X901803
X961803
X981803
X986803
X911803
X916803
X921803
X936803
X931803
X926803
X956803
X941803
X971803
X966803
X993000Y1491500
X997000Y1496000
X998126Y1503614
Y1508614
Y1513614
X1038126
X1033126
X1028126
X1048126
X1043126
X1003126
X1023126
X1053126
X1018126
X1058126
X1013126
X1008126
X1061675Y1510352
X1099575Y1509397
X1065210Y1506817
X1096039Y1505861
X1066638Y1502408
Y1472408
X1095567Y1471057
X1066638Y1467408
X1095567Y1466057
X1066638Y1462408
X1095567Y1461057
X1066638Y1457408
X1095567Y1456057
X1066638Y1452408
X1095567Y1451057
X1066638Y1447408
X1095567Y1446057
X1066638Y1442408
X1095567Y1441057
Y1436057
Y1431057
Y1426057
X1077933Y1411323
X1082933
X1087933
X1062400Y796500
X1057600
X1067200
X1062400Y791500
X1067200
X1057600
X1062400Y786500
X1067200
X1057600
X1062400Y781500
X1057600
X1035594Y776583
X1040394
X1057600Y776500
X1021194Y776483
X1016394
X1035594Y771783
X1040394
X1021194Y771683
X1016394
X1057400Y771600
X1035594Y766983
X1040394
X1021194Y766883
X1016394
X1038200Y762300
X1076142Y386839
X1075829Y380885
X1075627Y374973
X1012000Y371369
X1015537Y365911
X1065055Y241895
Y236895
Y231895
Y226895
Y221895
Y216895
Y211895
Y206895
Y201895
X1064500Y197500
X1073734Y195764
X1088734
X1083734
X1068734
X1093734
X1098734
X1078734
X1118734
X1123734
X1128734
X1183734
X1188734
X1193734
X1103734
X1113734
X1133734
X1138734
X1143734
X1148734
X1153734
X1158734
X1163734
X1168734
X1173734
X1178734
X1198734
X1100677Y398372
X1105477
X1124677Y398472
X1119877
X1105477Y403172
X1100677
X1119877Y403272
X1124677
X1105477Y407972
X1100677
X1124677Y408072
X1119877
X1105477Y418640
X1100677
X1124677Y418740
X1119877
X1100677Y423440
X1105477
X1119877Y423540
X1124677
X1105477Y428240
X1100677
X1119877Y428340
X1124677
X1155900Y1179300
X1151100
X1155900Y1184100
X1151100
Y1188900
X1155900
X1133500Y1196900
X1128700
X1109600Y1197100
X1114400
X1133500Y1201700
X1128700
X1109600Y1201900
X1114400
X1128700Y1206500
X1133500
X1109600Y1206700
X1114400
X1133300Y1216100
X1128500
X1109400Y1216300
X1114200
X1128500Y1220900
X1133300
X1109400Y1221100
X1114200
X1128500Y1225700
X1133300
X1114200Y1225900
X1109400
X1117200Y1346700
X1112000Y1480500
X1118000
X1115000Y1485000
X1103110Y1512932
X1197798Y1513685
X1192798
X1187798
X1127798
X1132798
X1137798
X1122798
X1117798
X1177798
X1112798
X1167798
X1162798
X1157798
X1152798
X1142798
X1147798
X1107798
X1182798
X1172798
X1288464
X1283464
X1293464
X1258464
X1253464
X1298464
X1273464
X1202798
X1268464
X1278464
X1263464
X1250500Y1510500
X1205500Y1509000
X1249000Y1504500
X1208000Y1502500
X1245500Y1500500
X1239783Y1499118
X1214783
X1229783
X1224783
X1219783
X1234783
X1218734Y195764
X1208734
X1213734
X1203734
X1225000Y194000
X1229000Y189500
X1230409Y182565
Y177565
Y172565
Y167565
Y162565
Y157565
Y152565
Y147565
Y142565
Y137565
Y132565
Y127565
Y122565
Y117565
Y112565
Y107565
Y102565
Y97565
Y92565
Y87565
Y82565
Y77565
Y72565
Y67565
Y62565
Y57565
Y52565
Y47565
Y42565
Y37565
Y32565
Y27565
Y22565
Y17565
Y12565
Y7565
X1248844Y6000
X1288844
X1293844
X1298844
X1278844
X1273844
X1238844
X1268844
X1243844
X1263844
X1283844
X1258844
X1253844
X1234500
X1328844
X1363844
X1348844
X1353844
X1398844
X1393844
X1343844
X1333844
X1388844
X1383844
X1378844
X1358844
X1373844
X1323844
X1318844
X1313844
X1308844
X1303844
X1338844
X1368844
X1383674Y1419000
X1383374Y1425000
X1380074Y1429500
X1385474
X1398500Y1513500
X1328464Y1513685
X1333464
X1313464
X1323464
X1308464
X1338464
X1343464
X1318464
X1348464
X1353464
X1358464
X1363464
X1368464
X1373464
X1378464
X1383464
X1388464
X1393464
X1303464
X1423464
X1413464
X1418464
X1408464
X1403500Y1513500
X1425890Y1510111
Y1505111
Y1500111
X1428500Y1494000
X1433500Y1490500
X1494716Y1490063
X1479716
X1469716
X1464716
X1459716
X1484716
X1474716
X1454716
X1449716
X1444716
X1439716
X1499716
X1489716
X1498844Y6000
X1403844
X1408844
X1413844
X1418844
X1463844
X1428844
X1493844
X1488844
X1483844
X1478844
X1473844
X1468844
X1423844
X1433844
X1438844
X1443844
X1448844
X1453844
X1458844
X1563844
X1568844
X1573844
X1578844
X1518844
X1583844
X1553844
X1513844
X1523844
X1508844
X1588844
X1593844
X1598844
X1548844
X1503844
X1543844
X1538844
X1533844
X1528844
X1558844
X1599716Y1490063
X1519716
X1524716
X1529716
X1534716
X1539716
X1509716
X1504716
X1594716
X1589716
X1584716
X1579716
X1574716
X1544716
X1549716
X1554716
X1559716
X1564716
X1514716
X1569716
X1680968Y1513685
X1665968
X1660968
X1690968
X1655968
X1650968
X1670968
X1695968
X1675968
X1685968
X1650488Y1509165
Y1504165
X1649500Y1497500
X1646000Y1492000
X1639716Y1490063
X1609716
X1604716
X1634716
X1614716
X1629716
X1624716
X1619716
X1667359Y439207
X1662559
Y434407
X1667359
X1662559Y429607
X1667359
X1618844Y6000
X1608844
X1613844
X1698844
X1693844
X1688844
X1683844
X1678844
X1673844
X1668844
X1663844
X1658844
X1623844
X1603844
X1653844
X1648844
X1643844
X1638844
X1633844
X1628844
X1738844
X1733844
X1728844
X1723844
X1718844
X1713844
X1748844
X1743844
X1708844
X1703844
X1758844
X1763844
X1768844
X1773844
X1778844
X1783844
X1798844
X1788844
X1793844
X1753844
X1751774Y430510
X1794915Y442185
Y446985
X1753959Y450607
X1799600Y451800
X1794915Y456985
Y461785
X1736359Y864107
X1741159
X1736359Y868907
X1741159
Y873707
X1736359
X1763926Y1419000
X1763626Y1425000
X1766526Y1429400
X1760326Y1429500
X1796004Y1513500
X1791004
X1786004
X1775968Y1513685
X1770968
X1765968
X1760968
X1755968
X1720968
X1725968
X1780968
X1715968
X1730968
X1705968
X1700968
X1710968
X1735968
X1740968
X1745968
X1750968
X1876582
X1886582
X1891582
X1871582
X1896582
X1881582
X1811004Y1513500
X1816004
X1801004
X1806004
X1821040Y1513315
X1826040
X1871157Y1509110
X1826500Y1506500
X1869500Y1503500
X1829500Y1501500
X1865500Y1500000
X1855256Y1499118
X1860256
X1835256
X1840256
X1850256
X1845256
X1869115Y895985
X1884115
X1869115Y891185
X1884115
X1898263Y888925
X1888663
X1893463
X1879100Y886300
X1873800
X1828363Y884925
X1893463Y883925
X1888663
X1898263
X1884115Y881185
X1869115
X1884115Y876385
X1869115
X1809915Y461785
Y456985
X1828863Y454725
X1819263
X1838463
X1833663
X1814463
X1824063
X1804900Y451800
X1828863Y449725
X1819263
X1814463
X1833663
X1838463
X1824063
X1809915Y446985
Y442185
X1853844Y6000
X1808844
X1898844
X1893844
X1888844
X1883844
X1878844
X1813844
X1818844
X1803844
X1823844
X1828844
X1868844
X1873844
X1833844
X1838844
X1843844
X1848844
X1858844
X1863844
X1908844
X1918844
X1923844
X1903844
X1913844
X1928843Y8985
Y13985
Y18985
Y23985
Y28985
Y33985
Y38985
Y43985
Y48985
Y53985
Y58985
Y63985
Y68985
Y73985
Y78985
Y83985
Y88985
Y93985
Y98985
Y103985
Y108985
Y113985
Y118985
Y123985
Y128985
Y133985
Y138985
Y143985
Y148985
Y153985
Y158985
Y163985
Y168985
Y173985
Y178985
Y183985
Y188985
Y193985
Y198985
Y203985
Y208985
Y213985
Y218985
Y223985
Y228985
Y233985
Y238985
Y243985
Y248985
Y253985
Y258985
Y263985
Y268985
Y273985
Y278985
Y283985
Y288985
Y293985
Y298985
Y303985
Y308985
Y313985
Y318985
Y323985
Y328985
Y333985
Y338985
Y343985
Y348985
Y353985
Y358985
Y363985
Y368985
Y373985
Y378985
Y383985
Y388985
Y393985
Y398985
Y403985
Y408985
Y413985
Y418985
Y423985
Y428985
Y433985
Y438985
Y443985
Y448985
Y453985
Y458985
Y463985
Y468985
Y473985
Y478985
Y483985
Y488985
Y493985
Y498985
Y503985
Y508985
Y513985
Y518985
Y523985
Y528985
Y533985
Y538985
Y543985
Y548985
Y553985
Y558985
Y563985
Y568985
Y573985
Y578985
Y583985
Y588985
Y593985
Y598985
Y603985
Y608985
Y613985
Y618985
Y623985
Y628985
Y633985
Y638985
Y643985
Y648985
Y653985
Y658985
Y663985
Y668985
Y673985
Y678985
Y683985
Y688985
Y693985
Y698985
Y703985
Y708985
Y713985
Y718985
Y723985
Y728985
Y733985
Y738985
Y743985
Y748985
Y753985
Y758985
Y763985
Y768985
Y773985
Y778985
Y783985
Y788985
Y793985
Y798985
Y803985
Y808985
Y813985
Y818985
Y823985
Y828985
Y833985
Y838985
Y843985
Y848985
Y853985
Y858985
Y863985
Y868985
Y873985
Y878985
X1907863Y883925
X1912663
X1903063
X1928843Y883985
X1912663Y888925
X1907863
X1903063
X1928843Y888985
Y893985
Y898985
Y903985
Y908985
Y913985
Y918985
Y923985
Y928985
Y933985
Y938985
Y943985
Y948985
Y953985
Y958985
Y963985
Y968985
Y973985
Y978985
Y983985
Y988985
Y993985
Y998985
Y1003985
Y1008985
Y1013985
Y1018985
Y1023985
Y1028985
Y1033985
Y1038985
Y1043985
Y1048985
Y1053985
Y1058985
Y1063985
Y1068985
Y1073985
Y1078985
Y1083985
Y1088985
Y1093985
Y1098985
Y1103985
Y1108985
Y1113985
Y1118985
Y1123985
Y1128985
Y1133985
Y1138985
Y1143985
Y1148985
Y1153985
Y1158985
Y1163985
Y1168985
Y1173985
Y1178985
Y1183985
Y1188985
Y1193985
Y1198985
Y1203985
Y1208985
Y1213985
Y1218985
Y1223985
Y1228985
Y1233985
Y1238985
Y1243985
Y1248985
Y1253985
Y1258985
Y1263985
Y1268985
Y1273985
Y1278985
Y1283985
Y1288985
Y1293985
Y1298985
Y1303985
Y1308985
Y1313985
Y1318985
Y1323985
Y1328985
Y1333985
Y1338985
Y1343985
Y1348985
Y1353985
Y1358985
Y1363985
Y1368985
Y1373985
Y1378985
Y1383985
Y1388985
Y1393985
Y1398985
Y1403985
Y1408985
Y1413985
Y1418985
Y1423985
Y1428985
Y1433985
Y1438985
Y1443985
Y1448985
X1926500Y1455000
X1920000Y1458000
X1917500Y1463500
X1917031Y1469134
Y1474134
Y1479134
Y1484134
Y1489134
Y1494134
Y1499134
Y1504134
Y1509134
X1901582Y1513685
X1911582
X1916582
X1906582
T07
X414000Y1362985
Y1372985
Y1382985
X426000
Y1372985
Y1362985
X438000
Y1372985
Y1382985
X450000
Y1372985
Y1362985
X462000
Y1372985
Y1382985
X474000
Y1372985
Y1362985
X486000
Y1372985
Y1382985
X498000
Y1372985
Y1362985
Y1352985
Y1342985
Y1332985
X510000Y1344485
Y1354485
Y1364485
Y1374485
Y1384485
X522000
Y1374485
Y1364485
Y1354485
Y1344485
X581800Y1321200
X589700
X581800Y1329100
X589700
Y1337000
X581800
Y1344900
X589700
X581800Y1352800
X589700
Y1360700
X581800
X589700Y1368600
X581800
Y1376500
X589700
X581800Y1384400
X589700
Y1392300
X581800
X589700Y1400200
X597600Y1408100
Y1400200
Y1392300
Y1384400
Y1376500
Y1368600
Y1360700
Y1352800
Y1344900
Y1337000
Y1329100
Y1321200
X594800Y1313500
X602700Y1297600
Y1305600
Y1313500
X605500Y1321200
Y1329100
Y1337000
Y1344900
Y1352800
Y1360700
Y1368600
Y1376500
Y1384400
Y1392300
Y1400200
Y1408100
X613400
Y1400200
Y1392300
Y1384400
Y1376500
Y1368600
Y1360700
Y1352800
Y1344900
Y1337000
Y1329100
Y1321200
X610600Y1313500
Y1305600
Y1297600
X629200Y1329100
X621300
Y1337000
X629200
Y1344900
X621300
Y1352800
X629200
Y1360700
X621300
Y1368600
X629200
Y1376500
X621300
X658200Y1376600
Y1368700
Y1360800
Y1352900
Y1345000
Y1337100
Y1329200
X666100
Y1337100
Y1345000
Y1352900
Y1360800
Y1368700
Y1376600
X675900Y1408200
Y1400300
Y1392400
X674000Y1384500
Y1376600
Y1368700
Y1360800
Y1352900
Y1345000
Y1337100
Y1329200
Y1321300
X678000Y1313900
Y1306000
Y1298000
X685900
Y1306000
Y1313900
X689800Y1321300
X681900
X689800Y1329200
X681900
Y1337100
X689800
X681900Y1345000
X689800
X681900Y1352900
X689800
X681900Y1360800
X689800
X681900Y1368700
X689800
Y1376600
X681900
Y1384500
X689800
X683800Y1392400
Y1400300
Y1408200
X699600
X691700
X699600Y1400300
X691700
Y1392400
X699600
X697100Y1384600
X697700Y1376600
Y1368700
Y1360800
Y1352900
Y1345000
Y1337100
Y1329200
Y1321300
X693800Y1313900
Y1306000
Y1298000
X705600Y1329200
Y1337100
Y1345000
Y1352900
Y1360800
Y1368700
Y1376600
X768867Y1399110
Y1391110
Y1383110
Y1375110
Y1367110
Y1359110
Y1351110
Y1343110
Y1335110
Y1327110
Y1319110
Y1311110
X775600Y1302400
X776867Y1311110
Y1319110
Y1327110
Y1335110
Y1343110
Y1351110
Y1359110
Y1367110
Y1375110
Y1383110
Y1391110
Y1399110
X782330Y1407929
X786600Y1378100
X782950Y1372703
X782223Y1339430
X786200Y1334100
Y1326100
X782056Y1297863
X790056
X798056
X794200Y1326100
Y1334100
X798223Y1339930
X790223
X790950Y1372703
X798950
X795000Y1377900
X790330Y1407929
X798330
X801000Y1333800
Y1325800
X820000Y1303500
X827000
X820000Y1310500
X827000
Y1317500
X820000
Y1324500
X827000
X820000Y1342000
X827000
X820000Y1349000
X827000
X820000Y1356000
X827000
X820000Y1363000
X827000
Y1379000
X820000
Y1386000
X827000
Y1393000
X820000
X834000Y1386000
Y1379000
Y1363000
Y1356000
Y1349000
Y1342000
Y1324500
Y1317500
Y1310500
Y1303500
X887800Y1327100
Y1335000
Y1342900
Y1350800
X886400Y1368100
Y1376000
X894300
Y1368100
X897800Y1359300
X890400Y1358900
X895200Y1351200
Y1343300
Y1335400
Y1327500
X903500Y1319400
X903100Y1327500
Y1335400
Y1343300
Y1351200
X905700Y1359300
X902200Y1368100
Y1376000
X918000
X910100
Y1368100
X918000
X913600Y1359300
X918900Y1351200
X911000
Y1343300
X918900
Y1335400
X911000
Y1327500
X918900
X910800Y1319700
X918700
X926600Y1303900
Y1311800
Y1319700
X926800Y1327500
Y1335400
Y1343300
Y1351200
X921500Y1359300
X929400
X937300
X934700Y1351200
Y1343300
Y1335400
Y1327500
X934500Y1319700
Y1311800
Y1303900
X942400
Y1311800
Y1319700
X958200
X950300
Y1311800
X958200
X950300Y1303900
X958200
X986700Y1307600
X986755Y1323816
X988900Y1366900
X989200Y1374800
X989100Y1381700
X989083Y1387764
X989509Y1393422
X999930Y1393070
X994700Y1385000
X999800Y1381600
X994400Y1377300
X999700Y1374500
X994300Y1370100
X999900Y1366800
X994200Y1362700
X997900Y1357400
X992500
X997900Y1352000
X992500
X997900Y1346600
X992500
X997900Y1341200
X992500
Y1335800
X997900
X991755Y1327716
X996055Y1324116
X991455Y1320416
X996400Y1315900
X991500Y1312100
X996200Y1307800
X991800Y1303400
X998600Y1300900
X1007100Y1301100
X1002700Y1305700
X1000200Y1311700
Y1320500
Y1328100
X1005629Y1333939
X1008870Y1361681
X1003367Y1361655
X1004217Y1389394
X1008298Y1393071
X1013692Y1389688
X1019829Y1389539
X1014306Y1361710
X1019829Y1361739
X1016429Y1333939
X1011029
X1019829Y1306139
X1011100Y1305300
X1014000Y1300600
X1020800Y1300400
X1021829Y1333939
X1034618Y1311189
Y1316589
Y1321989
X1037200Y1335000
X1031600Y1335100
X1034799Y1340183
X1037540Y1344964
X1034600Y1349600
X1036900Y1362600
X1031300Y1362700
X1034380Y1367469
X1037111Y1372380
X1034300Y1377200
X1042100Y1377100
X1047401Y1375084
X1039988Y1367352
X1044400Y1363100
X1042400Y1349500
X1048000Y1346100
X1043300Y1342500
X1044700Y1335500
X1040018Y1321989
X1045418
X1040018Y1316589
X1045418Y1311189
X1040018
X1050818
X1056218
X1050818Y1316589
X1056218
X1050818Y1321989
X1061618Y1311189
X1066407Y1313972
X1061618Y1316589
X1066491Y1319983
X1060218Y1321989
X1061081Y1327759
X1066481
X1061081Y1333159
X1066481
X1061081Y1338559
X1066481
Y1343959
X1061081
X1066481Y1349359
X1061081
X1066481Y1354759
X1061081
Y1360159
X1066481
Y1365559
X1061081
Y1370959
X1066481
Y1376359
X1061081
T08
X974015Y255906
Y261812
Y267717
Y278544
Y284449
Y290355
Y301182
Y307087
Y312993
X986614
Y307087
Y301182
Y290355
Y284449
Y278544
Y267717
Y261812
Y255906
X1002362
Y261812
Y267717
Y278544
Y284449
Y290355
Y301182
Y307087
Y312993
X1014960
Y307087
Y301182
Y290355
Y284449
Y278544
Y267717
Y261812
Y255906
X1030709Y312993
Y307087
Y301182
Y290355
Y284449
Y278544
Y267717
Y261812
Y255906
X1043307
Y261812
Y267717
Y278544
Y284449
Y290355
Y301182
Y307087
Y312993
X1101405Y1120040
X1108098
Y1132638
X1101405
X1119633
Y1120040
X1126326
Y1132638
T09
X70709Y1485118
X80709
X90709
X691181
X701181
X711181
X1217953
X1227953
X1237953
X1838425
X1848425
X1858425
T10
X294055Y1320472
Y1330472
Y1340472
Y1350472
X304055
Y1340472
Y1330472
Y1320472
X324055
Y1330472
Y1340472
Y1350472
X334055
Y1340472
Y1330472
Y1320472
X354055
Y1330472
Y1340472
Y1350472
X364055
Y1340472
Y1330472
Y1320472
X384055
Y1330472
Y1340472
Y1350472
X394055
Y1340472
Y1330472
Y1320472
X414055
Y1330472
Y1340472
Y1350472
X424055
Y1340472
Y1330472
Y1320472
X444055
Y1330472
Y1340472
Y1350472
X454055
Y1340472
Y1330472
Y1320472
X474055
Y1330472
Y1340472
Y1350472
X484055
Y1340472
Y1330472
Y1320472
T11
X167716Y1445275
Y1466929
X184252
Y1445275
X200787
Y1466929
X217322
Y1445275
X233858
Y1466929
X548031
Y1445275
X564567
Y1466929
X581102
Y1445275
X597637
Y1466929
X614173
Y1445275
X1314960
Y1466929
X1331496
Y1445275
X1348031
Y1466929
X1364566
Y1445275
X1381102
Y1466929
X1695275
Y1445275
X1711811
Y1466929
X1728346
Y1445275
X1744881
Y1466929
X1761417
Y1445275
T12
X173228Y55118
X421653Y94488
X670078Y55118
X1343701
X1592126Y94488
X1840551Y55118
T13
X111024Y39508
X235236
X359449
X483661
X607874
X732087
X1281693
X1405906
X1530118
X1654331
X1778543
X1902756
Y492264
X1778543
X1654331
X1530118
X1405906
X1281693
X732087
X607874
X483661
X359449
X235236
X111024
Y945020
X235236
X359449
X483661
X607874
X732087
X1281693
X1405906
X1530118
X1654331
X1778543
X1902756
T14
X111024Y188130
X235236
X359449
X483661
X607874
X732087
X1281693
X1405906
X1530118
X1654331
X1778543
X1902756
Y640886
X1778543
X1654331
X1530118
X1405906
X1281693
X732087
X607874
X483661
X359449
X235236
X111024
Y1093642
X235236
X359449
X483661
X607874
X732087
X1281693
X1405906
X1530118
X1654331
X1778543
X1902756
T15
X59400Y32600
X812347Y17406
X1187163Y158305
X1869500Y1461500
X1538001Y1511515
X885639
X390757
X63374Y1454500
T16
X266535Y1320472
X511535
T17
X173228Y122047
X670079
X1343701Y122046
X1840551
T18
X167716Y1495669
X233858
X548031
X614173
X1314960
X1381102
X1695275
X1761417
T19
X246535Y1320472
X531535
T20
X1104528Y1162257
T21
X1673917Y262992
X503248Y715748
M30
